FILE_TYPE = MACRO_DRAWING;
SET COLOR_WIRE YELLOW;
SET COLOR_PROP ORANGE;
SET COLOR_DOT WHITE;
SET COLOR_ARC YELLOW;
SET COLOR_BODY GREEN;
SET COLOR_NOTE PURPLE;
SET PROP_DISPLAY VALUE;
SET PAGE_NUMBER P192;
FORCEADD OFFPAGE..5
(-9125 1175);
FORCEPROP 2 LAST $XR0 80 
J 0
(-9349 1175);
DISPLAY 0.638298 (-9349 1175);
PAINT MONO (-9349 1175);
FORCEPROP 2 LAST CDS_LIB standard
J 0
(-9125 1175);
DISPLAY INVISIBLE (-9125 1175);
FORCEPROP 1 LAST OFFPAGE TRUE
J 0
(-8800 1050);
DISPLAY 0.872340 (-8800 1050);
PAINT GREEN (-8800 1050);
DISPLAY INVISIBLE (-8800 1050);
FORCEPROP 1 LAST COMMENT_BODY TRUE
J 0
(-9025 1100);
DISPLAY 0.872340 (-9025 1100);
PAINT GREEN (-9025 1100);
DISPLAY INVISIBLE (-9025 1100);
FORCEPROP 2 LAST PATH I211
J 0
(-9375 1225);
DISPLAY 1.021277 (-9375 1225);
DISPLAY INVISIBLE (-9375 1225);
FORCEADD OFFPAGE..1
(-9950 2900);
FORCEPROP 2 LAST $XR0 54 
J 0
(-10261 2900);
DISPLAY 0.638298 (-10261 2900);
PAINT MONO (-10261 2900);
FORCEPROP 2 LAST CDS_LIB standard
J 0
(-9950 2900);
DISPLAY INVISIBLE (-9950 2900);
FORCEPROP 1 LAST OFFPAGE TRUE
J 0
(-9625 2775);
DISPLAY 0.872340 (-9625 2775);
PAINT GREEN (-9625 2775);
DISPLAY INVISIBLE (-9625 2775);
FORCEPROP 1 LAST COMMENT_BODY TRUE
J 0
(-9825 2800);
DISPLAY 0.872340 (-9825 2800);
PAINT GREEN (-9825 2800);
DISPLAY INVISIBLE (-9825 2800);
FORCEPROP 2 LAST PATH I214
J 0
(-10150 2950);
DISPLAY 1.021277 (-10150 2950);
DISPLAY INVISIBLE (-10150 2950);
FORCEADD OFFPAGE..1
(-9950 3275);
FORCEPROP 2 LAST $XR0 54 
J 0
(-10261 3275);
DISPLAY 0.638298 (-10261 3275);
PAINT MONO (-10261 3275);
FORCEPROP 2 LAST CDS_LIB standard
J 0
(-9950 3275);
DISPLAY INVISIBLE (-9950 3275);
FORCEPROP 1 LAST OFFPAGE TRUE
J 0
(-9625 3150);
DISPLAY 0.872340 (-9625 3150);
PAINT GREEN (-9625 3150);
DISPLAY INVISIBLE (-9625 3150);
FORCEPROP 1 LAST COMMENT_BODY TRUE
J 0
(-9825 3175);
DISPLAY 0.872340 (-9825 3175);
PAINT GREEN (-9825 3175);
DISPLAY INVISIBLE (-9825 3175);
FORCEPROP 2 LAST PATH I215
J 0
(-10150 3325);
DISPLAY 1.021277 (-10150 3325);
DISPLAY INVISIBLE (-10150 3325);
FORCEADD Q_RES..1
(-8600 1025);
FORCEPROP 1 LAST LOCATION PR230
J 0
(-8825 1025);
DISPLAY 0.489362 (-8825 1025);
PAINT SKYBLUE (-8825 1025);
FORCEPROP 0 LAST $SEC 1
J 0
(-8650 1125);
DISPLAY 0.680851 (-8650 1125);
PAINT MONO (-8650 1125);
DISPLAY INVISIBLE (-8650 1125);
FORCEPROP 0 LAST CDS_SEC 1
J 0
(-8650 1125);
DISPLAY 1.021277 (-8650 1125);
DISPLAY INVISIBLE (-8650 1125);
FORCEPROP 1 LASTPIN (-8700 1025) $PN 1
J 0
(-8688 1037);
DISPLAY 0.489362 (-8688 1037);
PAINT MONO (-8688 1037);
FORCEPROP 1 LASTPIN (-8500 1025) $PN 2
J 0
(-8538 1037);
DISPLAY 0.489362 (-8538 1037);
PAINT MONO (-8538 1037);
FORCEPROP 1 LAST MATERIAL CHIP
J 0
(-8125 1050);
DISPLAY 0.489362 (-8125 1050);
PAINT SKYBLUE (-8125 1050);
FORCEPROP 1 LAST TOLERANCE 1%
J 0
(-8350 1050);
DISPLAY 0.489362 (-8350 1050);
PAINT SKYBLUE (-8350 1050);
FORCEPROP 1 LAST VALUE 40.2K
J 2
(-8375 1050);
DISPLAY 0.489362 (-8375 1050);
PAINT SKYBLUE (-8375 1050);
FORCEPROP 1 LAST PACK_TYPE 0402LF
J 0
(-8275 1050);
DISPLAY 0.489362 (-8275 1050);
PAINT SKYBLUE (-8275 1050);
FORCEPROP 2 LAST CDS_LIB pure_quanta
J 0
(-8600 1025);
DISPLAY INVISIBLE (-8600 1025);
FORCEPROP 1 LAST PATH I219
J 0
(-8650 1175);
DISPLAY 0.978723 (-8650 1175);
PAINT WHITE (-8650 1175);
DISPLAY INVISIBLE (-8650 1175);
FORCEPROP 1 LAST WATTAGE 1/16W
J 2
(-8225 925);
DISPLAY 0.510638 (-8225 925);
PAINT SKYBLUE (-8225 925);
DISPLAY INVISIBLE (-8225 925);
FORCEPROP 1 LAST PART_NUMBER TMP_QCS34022FB15
J 0
(-8475 975);
DISPLAY 0.510638 (-8475 975);
PAINT SKYBLUE (-8475 975);
DISPLAY INVISIBLE (-8475 975);
FORCEADD Q_RES..1
(-7275 850);
FORCEPROP 1 LAST LOCATION PR251
J 0
(-7325 900);
DISPLAY 0.489362 (-7325 900);
PAINT SKYBLUE (-7325 900);
FORCEPROP 0 LAST $SEC 1
J 0
(-7325 950);
DISPLAY 0.680851 (-7325 950);
PAINT MONO (-7325 950);
DISPLAY INVISIBLE (-7325 950);
FORCEPROP 0 LAST CDS_SEC 1
J 0
(-7325 950);
DISPLAY 1.021277 (-7325 950);
DISPLAY INVISIBLE (-7325 950);
FORCEPROP 1 LASTPIN (-7375 850) $PN 1
J 0
(-7363 862);
DISPLAY 0.489362 (-7363 862);
PAINT MONO (-7363 862);
FORCEPROP 1 LASTPIN (-7175 850) $PN 2
J 0
(-7213 862);
DISPLAY 0.489362 (-7213 862);
PAINT MONO (-7213 862);
FORCEPROP 1 LAST WATTAGE 1/16W
J 2
(-7100 750);
DISPLAY 0.489362 (-7100 750);
PAINT SKYBLUE (-7100 750);
FORCEPROP 1 LAST MATERIAL CHIP
J 0
(-7200 800);
DISPLAY 0.489362 (-7200 800);
PAINT SKYBLUE (-7200 800);
FORCEPROP 1 LAST TOLERANCE 5%
J 0
(-7425 875);
DISPLAY 0.489362 (-7425 875);
PAINT SKYBLUE (-7425 875);
FORCEPROP 1 LAST VALUE 0
J 2
(-7475 875);
DISPLAY 0.489362 (-7475 875);
PAINT SKYBLUE (-7475 875);
FORCEPROP 1 LAST PART_NUMBER CS00002JB38
J 0
(-7575 800);
DISPLAY 0.489362 (-7575 800);
PAINT SKYBLUE (-7575 800);
FORCEPROP 1 LAST PACK_TYPE 0402LF
J 0
(-7175 875);
DISPLAY 0.489362 (-7175 875);
PAINT SKYBLUE (-7175 875);
FORCEPROP 2 LAST CDS_LIB pure_quanta
J 0
(-7275 850);
DISPLAY INVISIBLE (-7275 850);
FORCEPROP 1 LAST PATH I220
J 0
(-7325 1000);
DISPLAY 0.978723 (-7325 1000);
PAINT WHITE (-7325 1000);
DISPLAY INVISIBLE (-7325 1000);
FORCEADD VCC_CORE..1
(-7525 925);
FORCEPROP 3 LASTPIN (-7525 875) SIG_NAME P12V_STBY\g
J 0
(-7515 885);
DISPLAY 0.659574 (-7515 885);
PAINT MONO (-7515 885);
DISPLAY INVISIBLE (-7515 885);
FORCEPROP 1 LAST HDL_POWER P12V_STBY
J 1
(-7525 975);
DISPLAY 0.489362 (-7525 975);
PAINT GREEN (-7525 975);
FORCEPROP 2 LAST CDS_LIB pure_quanta_power
J 0
(-7525 925);
DISPLAY INVISIBLE (-7525 925);
FORCEPROP 1 LAST PATH I221
J 0
(-7475 950);
DISPLAY 0.872340 (-7475 950);
PAINT AQUA (-7475 950);
DISPLAY INVISIBLE (-7475 950);
FORCEADD VCC_CORE..1
(-8450 1375);
FORCEPROP 3 LASTPIN (-8450 1325) SIG_NAME P3V3_STBY\g
J 0
(-8440 1335);
DISPLAY 0.659574 (-8440 1335);
PAINT MONO (-8440 1335);
DISPLAY INVISIBLE (-8440 1335);
FORCEPROP 1 LAST HDL_POWER P3V3_STBY
J 1
(-8450 1425);
DISPLAY 0.489362 (-8450 1425);
PAINT GREEN (-8450 1425);
FORCEPROP 2 LAST CDS_LIB pure_quanta_power
J 0
(-8450 1375);
DISPLAY INVISIBLE (-8450 1375);
FORCEPROP 1 LAST PATH I222
J 0
(-8400 1400);
DISPLAY 0.872340 (-8400 1400);
PAINT AQUA (-8400 1400);
DISPLAY INVISIBLE (-8400 1400);
FORCEADD Q_RES..1
(-7975 1125);
FORCEPROP 1 LAST LOCATION PR243
J 0
(-8200 1125);
DISPLAY 0.489362 (-8200 1125);
PAINT SKYBLUE (-8200 1125);
FORCEPROP 0 LAST $SEC 1
J 0
(-8025 1225);
DISPLAY 0.680851 (-8025 1225);
PAINT MONO (-8025 1225);
DISPLAY INVISIBLE (-8025 1225);
FORCEPROP 0 LAST CDS_SEC 1
J 0
(-8025 1225);
DISPLAY 1.021277 (-8025 1225);
DISPLAY INVISIBLE (-8025 1225);
FORCEPROP 1 LASTPIN (-8075 1125) $PN 1
J 0
(-8063 1137);
DISPLAY 0.489362 (-8063 1137);
PAINT MONO (-8063 1137);
FORCEPROP 1 LASTPIN (-7875 1125) $PN 2
J 0
(-7913 1137);
DISPLAY 0.489362 (-7913 1137);
PAINT MONO (-7913 1137);
FORCEPROP 1 LAST WATTAGE 1/16W
J 2
(-7600 1225);
DISPLAY 0.489362 (-7600 1225);
PAINT SKYBLUE (-7600 1225);
FORCEPROP 1 LAST MATERIAL CHIP
J 0
(-7850 1225);
DISPLAY 0.489362 (-7850 1225);
PAINT SKYBLUE (-7850 1225);
FORCEPROP 1 LAST TOLERANCE 5%
J 0
(-7800 1125);
DISPLAY 0.489362 (-7800 1125);
PAINT SKYBLUE (-7800 1125);
FORCEPROP 1 LAST VALUE 0
J 2
(-7825 1125);
DISPLAY 0.489362 (-7825 1125);
PAINT SKYBLUE (-7825 1125);
FORCEPROP 1 LAST PART_NUMBER CS00002JB38
J 0
(-7850 1175);
DISPLAY 0.489362 (-7850 1175);
PAINT SKYBLUE (-7850 1175);
FORCEPROP 1 LAST PACK_TYPE 0402LF
J 0
(-7725 1125);
DISPLAY 0.489362 (-7725 1125);
PAINT SKYBLUE (-7725 1125);
FORCEPROP 2 LAST CDS_LIB pure_quanta
J 0
(-7975 1125);
DISPLAY INVISIBLE (-7975 1125);
FORCEPROP 1 LAST PATH I223
J 0
(-8025 1275);
DISPLAY 0.978723 (-8025 1275);
PAINT WHITE (-8025 1275);
DISPLAY INVISIBLE (-8025 1275);
FORCEADD Q_RES..1
(-7975 1275);
FORCEPROP 1 LAST LOCATION PR242
J 0
(-8200 1275);
DISPLAY 0.489362 (-8200 1275);
PAINT SKYBLUE (-8200 1275);
FORCEPROP 0 LAST $SEC 1
J 0
(-8025 1375);
DISPLAY 0.680851 (-8025 1375);
PAINT MONO (-8025 1375);
DISPLAY INVISIBLE (-8025 1375);
FORCEPROP 0 LAST CDS_SEC 1
J 0
(-8025 1375);
DISPLAY 1.021277 (-8025 1375);
DISPLAY INVISIBLE (-8025 1375);
FORCEPROP 1 LASTPIN (-8075 1275) $PN 1
J 0
(-8063 1287);
DISPLAY 0.489362 (-8063 1287);
PAINT MONO (-8063 1287);
FORCEPROP 1 LASTPIN (-7875 1275) $PN 2
J 0
(-7913 1287);
DISPLAY 0.489362 (-7913 1287);
PAINT MONO (-7913 1287);
FORCEPROP 1 LAST WATTAGE 1/16W
J 2
(-7600 1375);
DISPLAY 0.489362 (-7600 1375);
PAINT SKYBLUE (-7600 1375);
FORCEPROP 1 LAST MATERIAL CHIP
J 0
(-7850 1375);
DISPLAY 0.489362 (-7850 1375);
PAINT SKYBLUE (-7850 1375);
FORCEPROP 1 LAST TOLERANCE 1%
J 0
(-7775 1275);
DISPLAY 0.489362 (-7775 1275);
PAINT SKYBLUE (-7775 1275);
FORCEPROP 1 LAST VALUE 1K
J 2
(-7800 1275);
DISPLAY 0.489362 (-7800 1275);
PAINT SKYBLUE (-7800 1275);
FORCEPROP 1 LAST PART_NUMBER TMP_QCS21002FB24
J 0
(-7850 1325);
DISPLAY 0.489362 (-7850 1325);
PAINT SKYBLUE (-7850 1325);
FORCEPROP 1 LAST PACK_TYPE 0402LF
J 0
(-7675 1275);
DISPLAY 0.489362 (-7675 1275);
PAINT SKYBLUE (-7675 1275);
FORCEPROP 2 LAST CDS_LIB pure_quanta
J 0
(-7975 1275);
DISPLAY INVISIBLE (-7975 1275);
FORCEPROP 1 LAST PATH I224
J 0
(-8025 1425);
DISPLAY 0.978723 (-8025 1425);
PAINT WHITE (-8025 1425);
DISPLAY INVISIBLE (-8025 1425);
FORCEADD UNIVERSAL_GND..1
(-7800 550);
FORCEPROP 3 LASTPIN (-7800 600) SIG_NAME GND\g
J 0
(-7790 610);
DISPLAY 0.659574 (-7790 610);
PAINT MONO (-7790 610);
DISPLAY INVISIBLE (-7790 610);
FORCEPROP 2 LAST CDS_LIB pure_quanta_power
J 0
(-7800 550);
PAINT MONO (-7800 550);
DISPLAY INVISIBLE (-7800 550);
FORCEPROP 1 LAST PATH I226
J 0
(-7725 550);
DISPLAY 0.872340 (-7725 550);
PAINT AQUA (-7725 550);
DISPLAY INVISIBLE (-7725 550);
FORCEPROP 1 LAST HDL_POWER GND
J 1
(-7775 475);
DISPLAY 0.872340 (-7775 475);
PAINT GREEN (-7775 475);
DISPLAY INVISIBLE (-7775 475);
FORCEADD Q_RES..2
(-8250 850);
FORCEPROP 1 LAST LOCATION PR231
J 0
(-8205 975);
DISPLAY 0.489362 (-8205 975);
PAINT SKYBLUE (-8205 975);
FORCEPROP 0 LAST $SEC 1
J 0
(-8200 1025);
DISPLAY 0.680851 (-8200 1025);
PAINT MONO (-8200 1025);
DISPLAY INVISIBLE (-8200 1025);
FORCEPROP 0 LAST CDS_SEC 1
J 0
(-8200 1025);
DISPLAY 1.021277 (-8200 1025);
DISPLAY INVISIBLE (-8200 1025);
FORCEPROP 1 LASTPIN (-8250 950) $PN 1
J 0
(-8245 912);
DISPLAY 0.489362 (-8245 912);
PAINT MONO (-8245 912);
FORCEPROP 1 LASTPIN (-8250 750) $PN 2
J 0
(-8245 760);
DISPLAY 0.489362 (-8245 760);
PAINT MONO (-8245 760);
FORCEPROP 1 LAST WATTAGE 1/16W
J 0
(-8210 825);
DISPLAY 0.489362 (-8210 825);
PAINT SKYBLUE (-8210 825);
FORCEPROP 1 LAST MATERIAL CHIP
J 0
(-8210 775);
DISPLAY 0.489362 (-8210 775);
PAINT SKYBLUE (-8210 775);
FORCEPROP 1 LAST TOLERANCE 1%
J 0
(-8205 875);
DISPLAY 0.489362 (-8205 875);
PAINT SKYBLUE (-8205 875);
FORCEPROP 1 LAST VALUE 10K
J 0
(-8205 925);
DISPLAY 0.489362 (-8205 925);
PAINT SKYBLUE (-8205 925);
FORCEPROP 1 LAST PACK_TYPE 0402LF
J 0
(-8210 675);
DISPLAY 0.489362 (-8210 675);
PAINT SKYBLUE (-8210 675);
FORCEPROP 1 LAST PART_NUMBER TMP_QCS31002FB26
J 0
(-8210 725);
DISPLAY 0.489362 (-8210 725);
PAINT SKYBLUE (-8210 725);
FORCEPROP 2 LAST CDS_LIB pure_quanta
J 0
(-8250 850);
DISPLAY INVISIBLE (-8250 850);
FORCEPROP 1 LAST PATH I227
J 0
(-8200 1025);
DISPLAY 0.978723 (-8200 1025);
PAINT WHITE (-8200 1025);
DISPLAY INVISIBLE (-8200 1025);
FORCEADD Q_CAP..1
(-7800 875);
FORCEPROP 1 LAST LOCATION PC357
J 0
(-7750 1000);
DISPLAY 0.489362 (-7750 1000);
PAINT SKYBLUE (-7750 1000);
FORCEPROP 0 LAST $SEC 1
J 0
(-7750 1050);
DISPLAY 0.680851 (-7750 1050);
PAINT MONO (-7750 1050);
DISPLAY INVISIBLE (-7750 1050);
FORCEPROP 0 LAST CDS_SEC 1
J 0
(-7750 1050);
DISPLAY 1.021277 (-7750 1050);
DISPLAY INVISIBLE (-7750 1050);
FORCEPROP 1 LASTPIN (-7800 975) $PN 1
J 0
(-7790 955);
DISPLAY 0.489362 (-7790 955);
PAINT MONO (-7790 955);
FORCEPROP 1 LASTPIN (-7800 775) $PN 2
J 0
(-7790 755);
DISPLAY 0.489362 (-7790 755);
PAINT MONO (-7790 755);
FORCEPROP 1 LAST MATERIAL X7R
J 0
(-7750 800);
DISPLAY 0.489362 (-7750 800);
PAINT SKYBLUE (-7750 800);
FORCEPROP 1 LAST TOLERANCE 10%
J 0
(-7750 850);
DISPLAY 0.489362 (-7750 850);
PAINT SKYBLUE (-7750 850);
FORCEPROP 1 LAST VALUE 0.1UF
J 0
(-7750 950);
DISPLAY 0.489362 (-7750 950);
PAINT SKYBLUE (-7750 950);
FORCEPROP 1 LAST VOLTAGE 25V
J 0
(-7750 900);
DISPLAY 0.489362 (-7750 900);
PAINT SKYBLUE (-7750 900);
FORCEPROP 1 LAST PACK_TYPE 0402
J 0
(-7750 750);
DISPLAY 0.489362 (-7750 750);
PAINT SKYBLUE (-7750 750);
FORCEPROP 1 LAST PART_NUMBER CH4104K1B00
J 0
(-7750 700);
DISPLAY 0.489362 (-7750 700);
PAINT SKYBLUE (-7750 700);
FORCEPROP 2 LAST CDS_LIB pure_quanta
J 0
(-7800 875);
DISPLAY INVISIBLE (-7800 875);
FORCEPROP 1 LAST PATH I228
J 0
(-7750 1025);
DISPLAY 0.978723 (-7750 1025);
PAINT WHITE (-7750 1025);
DISPLAY INVISIBLE (-7750 1025);
FORCEADD Q_CAP..2
(-7175 1275);
FORCEPROP 1 LAST LOCATION PC362
J 1
(-7375 1275);
DISPLAY 0.489362 (-7375 1275);
PAINT SKYBLUE (-7375 1275);
FORCEPROP 0 LAST $SEC 1
J 0
(-7225 1375);
DISPLAY 0.680851 (-7225 1375);
PAINT MONO (-7225 1375);
DISPLAY INVISIBLE (-7225 1375);
FORCEPROP 0 LAST CDS_SEC 1
J 0
(-7225 1375);
DISPLAY 1.021277 (-7225 1375);
DISPLAY INVISIBLE (-7225 1375);
FORCEPROP 1 LASTPIN (-7275 1275) $PN 1
J 0
(-7285 1290);
DISPLAY 0.489362 (-7285 1290);
PAINT MONO (-7285 1290);
FORCEPROP 1 LASTPIN (-7075 1275) $PN 2
J 0
(-7090 1290);
DISPLAY 0.489362 (-7090 1290);
PAINT MONO (-7090 1290);
FORCEPROP 1 LAST MATERIAL EMPTY
J 0
(-6700 1275);
DISPLAY 0.489362 (-6700 1275);
PAINT RED (-6700 1275);
FORCEPROP 1 LAST TOLERANCE 5%
J 2
(-6525 1225);
DISPLAY 0.489362 (-6525 1225);
PAINT SKYBLUE (-6525 1225);
FORCEPROP 1 LAST VALUE 1000PF
J 2
(-6850 1275);
DISPLAY 0.489362 (-6850 1275);
PAINT SKYBLUE (-6850 1275);
FORCEPROP 1 LAST PART_NUMBER TMP_QCH21006JB10
J 1
(-6900 1225);
DISPLAY 0.489362 (-6900 1225);
PAINT SKYBLUE (-6900 1225);
FORCEPROP 1 LAST VOLTAGE 50V
J 0
(-6825 1275);
DISPLAY 0.489362 (-6825 1275);
PAINT SKYBLUE (-6825 1275);
FORCEPROP 1 LAST PACK_TYPE 0402
J 1
(-6675 1225);
DISPLAY 0.489362 (-6675 1225);
PAINT SKYBLUE (-6675 1225);
FORCEPROP 2 LAST CDS_LIB pure_quanta
J 0
(-7175 1275);
DISPLAY INVISIBLE (-7175 1275);
FORCEPROP 1 LAST PATH I230
J 0
(-7175 1475);
DISPLAY 0.978723 (-7175 1475);
PAINT WHITE (-7175 1475);
DISPLAY INVISIBLE (-7175 1475);
FORCEADD Q_CAP..1
(-7225 3100);
FORCEPROP 1 LAST LOCATION PC361
J 0
(-7175 3225);
DISPLAY 0.489362 (-7175 3225);
PAINT SKYBLUE (-7175 3225);
FORCEPROP 0 LAST $SEC 1
J 0
(-7175 3225);
DISPLAY 0.680851 (-7175 3225);
PAINT MONO (-7175 3225);
DISPLAY INVISIBLE (-7175 3225);
FORCEPROP 0 LAST CDS_SEC 1
J 0
(-7175 3225);
DISPLAY 1.021277 (-7175 3225);
DISPLAY INVISIBLE (-7175 3225);
FORCEPROP 1 LASTPIN (-7225 3200) $PN 1
J 0
(-7215 3180);
DISPLAY 0.489362 (-7215 3180);
PAINT MONO (-7215 3180);
FORCEPROP 1 LASTPIN (-7225 3000) $PN 2
J 0
(-7215 2980);
DISPLAY 0.489362 (-7215 2980);
PAINT MONO (-7215 2980);
FORCEPROP 1 LAST MATERIAL X7R
J 0
(-7175 3025);
DISPLAY 0.489362 (-7175 3025);
PAINT SKYBLUE (-7175 3025);
FORCEPROP 1 LAST TOLERANCE 10%
J 0
(-7175 3075);
DISPLAY 0.489362 (-7175 3075);
PAINT SKYBLUE (-7175 3075);
FORCEPROP 1 LAST VALUE 3300PF
J 0
(-7175 3175);
DISPLAY 0.489362 (-7175 3175);
PAINT SKYBLUE (-7175 3175);
FORCEPROP 1 LAST PART_NUMBER TMP_QCH2336K1B12
J 0
(-7175 2925);
DISPLAY 0.489362 (-7175 2925);
PAINT SKYBLUE (-7175 2925);
FORCEPROP 1 LAST VOLTAGE 50V
J 0
(-7175 3125);
DISPLAY 0.489362 (-7175 3125);
PAINT SKYBLUE (-7175 3125);
FORCEPROP 1 LAST PACK_TYPE 0402
J 0
(-7175 2975);
DISPLAY 0.489362 (-7175 2975);
PAINT SKYBLUE (-7175 2975);
FORCEPROP 2 LAST CDS_LIB pure_quanta
J 0
(-7225 3100);
DISPLAY INVISIBLE (-7225 3100);
FORCEPROP 1 LAST PATH I245
J 0
(-7175 3250);
DISPLAY 0.978723 (-7175 3250);
PAINT WHITE (-7175 3250);
DISPLAY INVISIBLE (-7175 3250);
FORCEADD Q_RES..1
(-7675 3275);
FORCEPROP 1 LAST LOCATION PR246
J 0
(-7725 3325);
DISPLAY 0.489362 (-7725 3325);
PAINT SKYBLUE (-7725 3325);
FORCEPROP 0 LAST $SEC 1
J 0
(-7725 3375);
DISPLAY 0.680851 (-7725 3375);
PAINT MONO (-7725 3375);
DISPLAY INVISIBLE (-7725 3375);
FORCEPROP 0 LAST CDS_SEC 1
J 0
(-7725 3375);
DISPLAY 1.021277 (-7725 3375);
DISPLAY INVISIBLE (-7725 3375);
FORCEPROP 1 LASTPIN (-7775 3275) $PN 1
J 0
(-7763 3287);
DISPLAY 0.489362 (-7763 3287);
PAINT MONO (-7763 3287);
FORCEPROP 1 LASTPIN (-7575 3275) $PN 2
J 0
(-7613 3287);
DISPLAY 0.489362 (-7613 3287);
PAINT MONO (-7613 3287);
FORCEPROP 1 LAST WATTAGE 1/16W
J 2
(-7450 3300);
DISPLAY 0.489362 (-7450 3300);
PAINT SKYBLUE (-7450 3300);
FORCEPROP 1 LAST MATERIAL CHIP
J 0
(-7550 3225);
DISPLAY 0.489362 (-7550 3225);
PAINT SKYBLUE (-7550 3225);
FORCEPROP 1 LAST TOLERANCE 5%
J 0
(-7850 3300);
DISPLAY 0.489362 (-7850 3300);
PAINT SKYBLUE (-7850 3300);
FORCEPROP 1 LAST VALUE 10
J 2
(-7900 3300);
DISPLAY 0.489362 (-7900 3300);
PAINT SKYBLUE (-7900 3300);
FORCEPROP 1 LAST PART_NUMBER TMP_QCS01002JB22
J 0
(-8075 3200);
DISPLAY 0.489362 (-8075 3200);
PAINT SKYBLUE (-8075 3200);
FORCEPROP 1 LAST PACK_TYPE 0402LF
J 0
(-7575 3175);
DISPLAY 0.489362 (-7575 3175);
PAINT SKYBLUE (-7575 3175);
FORCEPROP 2 LAST CDS_LIB pure_quanta
J 0
(-7675 3275);
DISPLAY INVISIBLE (-7675 3275);
FORCEPROP 1 LAST PATH I246
J 0
(-7725 3425);
DISPLAY 0.978723 (-7725 3425);
PAINT WHITE (-7725 3425);
DISPLAY INVISIBLE (-7725 3425);
FORCEADD Q_CAP..1
(-7275 4200);
FORCEPROP 1 LAST LOCATION PC358
J 0
(-7225 4325);
DISPLAY 0.489362 (-7225 4325);
PAINT SKYBLUE (-7225 4325);
FORCEPROP 0 LAST $SEC 1
J 0
(-7225 4325);
DISPLAY 0.680851 (-7225 4325);
PAINT MONO (-7225 4325);
DISPLAY INVISIBLE (-7225 4325);
FORCEPROP 0 LAST CDS_SEC 1
J 0
(-7225 4325);
DISPLAY 1.021277 (-7225 4325);
DISPLAY INVISIBLE (-7225 4325);
FORCEPROP 1 LASTPIN (-7275 4300) $PN 1
J 0
(-7265 4280);
DISPLAY 0.489362 (-7265 4280);
PAINT MONO (-7265 4280);
FORCEPROP 1 LASTPIN (-7275 4100) $PN 2
J 0
(-7265 4080);
DISPLAY 0.489362 (-7265 4080);
PAINT MONO (-7265 4080);
FORCEPROP 1 LAST PART_NUMBER TMP_QCH2336K1B12
J 0
(-7225 4025);
DISPLAY 0.489362 (-7225 4025);
PAINT SKYBLUE (-7225 4025);
FORCEPROP 1 LAST MATERIAL X7R
J 0
(-7225 4125);
DISPLAY 0.489362 (-7225 4125);
PAINT SKYBLUE (-7225 4125);
FORCEPROP 1 LAST TOLERANCE 10%
J 0
(-7225 4175);
DISPLAY 0.489362 (-7225 4175);
PAINT SKYBLUE (-7225 4175);
FORCEPROP 1 LAST VALUE 3300PF
J 0
(-7225 4275);
DISPLAY 0.489362 (-7225 4275);
PAINT SKYBLUE (-7225 4275);
FORCEPROP 1 LAST VOLTAGE 50V
J 0
(-7225 4225);
DISPLAY 0.489362 (-7225 4225);
PAINT SKYBLUE (-7225 4225);
FORCEPROP 1 LAST PACK_TYPE 0402
J 0
(-7225 4075);
DISPLAY 0.489362 (-7225 4075);
PAINT SKYBLUE (-7225 4075);
FORCEPROP 2 LAST CDS_LIB pure_quanta
J 0
(-7275 4200);
DISPLAY INVISIBLE (-7275 4200);
FORCEPROP 1 LAST PATH I247
J 0
(-7225 4350);
DISPLAY 0.978723 (-7225 4350);
PAINT WHITE (-7225 4350);
DISPLAY INVISIBLE (-7225 4350);
FORCEADD OFFPAGE..1
(-9950 4375);
FORCEPROP 2 LAST $XR0 54 
J 0
(-10231 4375);
DISPLAY 0.638298 (-10231 4375);
PAINT MONO (-10231 4375);
FORCEPROP 2 LAST CDS_LIB standard
J 0
(-9950 4375);
DISPLAY INVISIBLE (-9950 4375);
FORCEPROP 1 LAST OFFPAGE TRUE
J 0
(-9625 4250);
DISPLAY 0.872340 (-9625 4250);
PAINT GREEN (-9625 4250);
DISPLAY INVISIBLE (-9625 4250);
FORCEPROP 1 LAST COMMENT_BODY TRUE
J 0
(-9825 4275);
DISPLAY 0.872340 (-9825 4275);
PAINT GREEN (-9825 4275);
DISPLAY INVISIBLE (-9825 4275);
FORCEPROP 2 LAST PATH I248
J 0
(-10225 4425);
DISPLAY 1.021277 (-10225 4425);
DISPLAY INVISIBLE (-10225 4425);
FORCEADD OFFPAGE..6
(-8350 5075);
FORCEPROP 2 LAST $XR1 186 
J 0
(-8750 5075);
DISPLAY 0.638298 (-8750 5075);
PAINT MONO (-8750 5075);
FORCEPROP 2 LAST $XR0 118 
J 0
(-8630 5075);
DISPLAY 0.638298 (-8630 5075);
PAINT MONO (-8630 5075);
FORCEPROP 2 LAST CDS_LIB standard
J 0
(-8350 5075);
DISPLAY INVISIBLE (-8350 5075);
FORCEPROP 1 LAST OFFPAGE TRUE
J 0
(-8025 4950);
DISPLAY 0.872340 (-8025 4950);
PAINT GREEN (-8025 4950);
DISPLAY INVISIBLE (-8025 4950);
FORCEPROP 1 LAST COMMENT_BODY TRUE
J 0
(-8250 5000);
DISPLAY 0.872340 (-8250 5000);
PAINT GREEN (-8250 5000);
DISPLAY INVISIBLE (-8250 5000);
FORCEPROP 2 LAST PATH I253
J 0
(-8625 5125);
DISPLAY 1.021277 (-8625 5125);
DISPLAY INVISIBLE (-8625 5125);
FORCEADD OFFPAGE..1
(-8350 5225);
FORCEPROP 2 LAST $XR1 186 
J 0
(-8752 5225);
DISPLAY 0.638298 (-8752 5225);
PAINT MONO (-8752 5225);
FORCEPROP 2 LAST $XR0 118 
J 0
(-8632 5225);
DISPLAY 0.638298 (-8632 5225);
PAINT MONO (-8632 5225);
FORCEPROP 2 LAST CDS_LIB standard
J 0
(-8350 5225);
DISPLAY INVISIBLE (-8350 5225);
FORCEPROP 1 LAST OFFPAGE TRUE
J 0
(-8025 5100);
DISPLAY 0.872340 (-8025 5100);
PAINT GREEN (-8025 5100);
DISPLAY INVISIBLE (-8025 5100);
FORCEPROP 1 LAST COMMENT_BODY TRUE
J 0
(-8225 5125);
DISPLAY 0.872340 (-8225 5125);
PAINT GREEN (-8225 5125);
DISPLAY INVISIBLE (-8225 5125);
FORCEPROP 2 LAST PATH I254
J 0
(-8600 5275);
DISPLAY 1.021277 (-8600 5275);
DISPLAY INVISIBLE (-8600 5275);
FORCEADD OFFPAGE..1
(-8850 6225);
FORCEPROP 2 LAST $XR0 81 
J 0
(-9071 6225);
DISPLAY 0.638298 (-9071 6225);
PAINT MONO (-9071 6225);
FORCEPROP 2 LAST PATH I259
J 0
(-9100 6275);
DISPLAY 1.021277 (-9100 6275);
DISPLAY INVISIBLE (-9100 6275);
FORCEPROP 1 LAST COMMENT_BODY TRUE
J 0
(-8725 6125);
DISPLAY 0.872340 (-8725 6125);
PAINT GREEN (-8725 6125);
DISPLAY INVISIBLE (-8725 6125);
FORCEPROP 1 LAST OFFPAGE TRUE
J 0
(-8525 6100);
DISPLAY 0.872340 (-8525 6100);
PAINT GREEN (-8525 6100);
DISPLAY INVISIBLE (-8525 6100);
FORCEPROP 2 LAST CDS_LIB standard
J 0
(-8850 6225);
DISPLAY INVISIBLE (-8850 6225);
FORCEADD OFFPAGE..5
(-8850 6375);
FORCEPROP 2 LAST $XR0 80 
J 0
(-9104 6375);
DISPLAY 0.638298 (-9104 6375);
PAINT MONO (-9104 6375);
FORCEPROP 2 LAST PATH I260
J 0
(-9100 6425);
DISPLAY 1.021277 (-9100 6425);
DISPLAY INVISIBLE (-9100 6425);
FORCEPROP 1 LAST COMMENT_BODY TRUE
J 0
(-8750 6300);
DISPLAY 0.872340 (-8750 6300);
PAINT GREEN (-8750 6300);
DISPLAY INVISIBLE (-8750 6300);
FORCEPROP 1 LAST OFFPAGE TRUE
J 0
(-8525 6250);
DISPLAY 0.872340 (-8525 6250);
PAINT GREEN (-8525 6250);
DISPLAY INVISIBLE (-8525 6250);
FORCEPROP 2 LAST CDS_LIB standard
J 0
(-8850 6375);
DISPLAY INVISIBLE (-8850 6375);
FORCEADD Q_RES..1
(-7725 4375);
FORCEPROP 1 LAST LOCATION PR245
J 0
(-7750 4425);
DISPLAY 0.489362 (-7750 4425);
PAINT SKYBLUE (-7750 4425);
FORCEPROP 0 LAST $SEC 1
J 0
(-7775 4475);
DISPLAY 0.680851 (-7775 4475);
PAINT MONO (-7775 4475);
DISPLAY INVISIBLE (-7775 4475);
FORCEPROP 0 LAST CDS_SEC 1
J 0
(-7775 4475);
DISPLAY 1.021277 (-7775 4475);
DISPLAY INVISIBLE (-7775 4475);
FORCEPROP 1 LASTPIN (-7825 4375) $PN 1
J 0
(-7813 4387);
DISPLAY 0.489362 (-7813 4387);
PAINT MONO (-7813 4387);
FORCEPROP 1 LASTPIN (-7625 4375) $PN 2
J 0
(-7663 4387);
DISPLAY 0.489362 (-7663 4387);
PAINT MONO (-7663 4387);
FORCEPROP 1 LAST PACK_TYPE 0402LF
J 0
(-7575 4300);
DISPLAY 0.489362 (-7575 4300);
PAINT SKYBLUE (-7575 4300);
FORCEPROP 1 LAST WATTAGE 1/16W
J 2
(-7475 4425);
DISPLAY 0.489362 (-7475 4425);
PAINT SKYBLUE (-7475 4425);
FORCEPROP 1 LAST MATERIAL CHIP
J 0
(-7575 4350);
DISPLAY 0.489362 (-7575 4350);
PAINT SKYBLUE (-7575 4350);
FORCEPROP 1 LAST TOLERANCE 5%
J 0
(-7875 4400);
DISPLAY 0.489362 (-7875 4400);
PAINT SKYBLUE (-7875 4400);
FORCEPROP 1 LAST VALUE 10
J 2
(-7925 4400);
DISPLAY 0.489362 (-7925 4400);
PAINT SKYBLUE (-7925 4400);
FORCEPROP 1 LAST PART_NUMBER TMP_QCS01002JB22
J 0
(-8100 4300);
DISPLAY 0.489362 (-8100 4300);
PAINT SKYBLUE (-8100 4300);
FORCEPROP 2 LAST CDS_LIB pure_quanta
J 0
(-7725 4375);
DISPLAY INVISIBLE (-7725 4375);
FORCEPROP 1 LAST PATH I271
J 0
(-7775 4525);
DISPLAY 0.978723 (-7775 4525);
PAINT WHITE (-7775 4525);
DISPLAY INVISIBLE (-7775 4525);
FORCEADD Q_RES..1
(-7375 5225);
FORCEPROP 1 LAST LOCATION PR248
J 0
(-7625 5225);
DISPLAY 0.489362 (-7625 5225);
PAINT SKYBLUE (-7625 5225);
FORCEPROP 0 LAST $SEC 1
J 0
(-7425 5325);
DISPLAY 0.680851 (-7425 5325);
PAINT MONO (-7425 5325);
DISPLAY INVISIBLE (-7425 5325);
FORCEPROP 0 LAST CDS_SEC 1
J 0
(-7425 5325);
DISPLAY 1.021277 (-7425 5325);
DISPLAY INVISIBLE (-7425 5325);
FORCEPROP 1 LASTPIN (-7475 5225) $PN 1
J 0
(-7463 5237);
DISPLAY 0.489362 (-7463 5237);
PAINT MONO (-7463 5237);
FORCEPROP 1 LASTPIN (-7275 5225) $PN 2
J 0
(-7313 5237);
DISPLAY 0.489362 (-7313 5237);
PAINT MONO (-7313 5237);
FORCEPROP 1 LAST WATTAGE 1/16W
J 2
(-7450 5175);
DISPLAY 0.489362 (-7450 5175);
PAINT SKYBLUE (-7450 5175);
FORCEPROP 1 LAST MATERIAL CHIP
J 0
(-7700 5175);
DISPLAY 0.489362 (-7700 5175);
PAINT SKYBLUE (-7700 5175);
FORCEPROP 1 LAST TOLERANCE 5%
J 0
(-7350 5175);
DISPLAY 0.489362 (-7350 5175);
PAINT SKYBLUE (-7350 5175);
FORCEPROP 1 LAST VALUE 0
J 2
(-7375 5175);
DISPLAY 0.489362 (-7375 5175);
PAINT SKYBLUE (-7375 5175);
FORCEPROP 1 LAST PART_NUMBER CS00002JB38
J 0
(-8050 5175);
DISPLAY 0.489362 (-8050 5175);
PAINT SKYBLUE (-8050 5175);
FORCEPROP 1 LAST PACK_TYPE 0402LF
J 0
(-7275 5175);
DISPLAY 0.489362 (-7275 5175);
PAINT SKYBLUE (-7275 5175);
FORCEPROP 2 LAST CDS_LIB pure_quanta
J 0
(-7375 5225);
DISPLAY INVISIBLE (-7375 5225);
FORCEPROP 1 LAST PATH I273
J 0
(-7425 5375);
DISPLAY 0.978723 (-7425 5375);
PAINT WHITE (-7425 5375);
DISPLAY INVISIBLE (-7425 5375);
FORCEADD Q_CAP..2
(-7250 6100);
FORCEPROP 1 LAST LOCATION PC359
J 1
(-7425 6100);
DISPLAY 0.489362 (-7425 6100);
PAINT SKYBLUE (-7425 6100);
FORCEPROP 0 LAST $SEC 1
J 0
(-7300 6200);
DISPLAY 0.680851 (-7300 6200);
PAINT MONO (-7300 6200);
DISPLAY INVISIBLE (-7300 6200);
FORCEPROP 0 LAST CDS_SEC 1
J 0
(-7300 6200);
DISPLAY 1.021277 (-7300 6200);
DISPLAY INVISIBLE (-7300 6200);
FORCEPROP 1 LASTPIN (-7350 6100) $PN 1
J 0
(-7360 6115);
DISPLAY 0.489362 (-7360 6115);
PAINT MONO (-7360 6115);
FORCEPROP 1 LASTPIN (-7150 6100) $PN 2
J 0
(-7165 6115);
DISPLAY 0.489362 (-7165 6115);
PAINT MONO (-7165 6115);
FORCEPROP 1 LAST MATERIAL X7R
J 0
(-6775 6100);
DISPLAY 0.489362 (-6775 6100);
PAINT SKYBLUE (-6775 6100);
FORCEPROP 1 LAST TOLERANCE 5%
J 2
(-6600 6050);
DISPLAY 0.489362 (-6600 6050);
PAINT SKYBLUE (-6600 6050);
FORCEPROP 1 LAST VALUE 1000PF
J 2
(-6925 6100);
DISPLAY 0.489362 (-6925 6100);
PAINT SKYBLUE (-6925 6100);
FORCEPROP 1 LAST PART_NUMBER TMP_QCH21006JB10
J 1
(-6975 6050);
DISPLAY 0.489362 (-6975 6050);
PAINT SKYBLUE (-6975 6050);
FORCEPROP 1 LAST VOLTAGE 50V
J 0
(-6900 6100);
DISPLAY 0.489362 (-6900 6100);
PAINT SKYBLUE (-6900 6100);
FORCEPROP 1 LAST PACK_TYPE 0402
J 1
(-6750 6050);
DISPLAY 0.489362 (-6750 6050);
PAINT SKYBLUE (-6750 6050);
FORCEPROP 2 LAST CDS_LIB pure_quanta
J 0
(-7250 6100);
DISPLAY INVISIBLE (-7250 6100);
FORCEPROP 1 LAST PATH I274
J 0
(-7250 6300);
DISPLAY 0.978723 (-7250 6300);
PAINT WHITE (-7250 6300);
DISPLAY INVISIBLE (-7250 6300);
FORCEADD Q_RES..1
(-8075 6225);
FORCEPROP 1 LAST LOCATION PR235
J 0
(-8275 6225);
DISPLAY 0.489362 (-8275 6225);
PAINT SKYBLUE (-8275 6225);
FORCEPROP 0 LAST $SEC 1
J 0
(-8125 6325);
DISPLAY 0.680851 (-8125 6325);
PAINT MONO (-8125 6325);
DISPLAY INVISIBLE (-8125 6325);
FORCEPROP 0 LAST CDS_SEC 1
J 0
(-8125 6325);
DISPLAY 1.021277 (-8125 6325);
DISPLAY INVISIBLE (-8125 6325);
FORCEPROP 1 LASTPIN (-8175 6225) $PN 1
J 0
(-8163 6237);
DISPLAY 0.489362 (-8163 6237);
PAINT MONO (-8163 6237);
FORCEPROP 1 LASTPIN (-7975 6225) $PN 2
J 0
(-8013 6237);
DISPLAY 0.489362 (-8013 6237);
PAINT MONO (-8013 6237);
FORCEPROP 1 LAST WATTAGE 1/16W
J 2
(-7700 6325);
DISPLAY 0.489362 (-7700 6325);
PAINT SKYBLUE (-7700 6325);
FORCEPROP 1 LAST MATERIAL CHIP
J 0
(-7950 6325);
DISPLAY 0.489362 (-7950 6325);
PAINT SKYBLUE (-7950 6325);
FORCEPROP 1 LAST TOLERANCE 5%
J 0
(-7900 6225);
DISPLAY 0.489362 (-7900 6225);
PAINT SKYBLUE (-7900 6225);
FORCEPROP 1 LAST VALUE 0
J 2
(-7925 6225);
DISPLAY 0.489362 (-7925 6225);
PAINT SKYBLUE (-7925 6225);
FORCEPROP 1 LAST PART_NUMBER CS00002JB38
J 0
(-7950 6275);
DISPLAY 0.489362 (-7950 6275);
PAINT SKYBLUE (-7950 6275);
FORCEPROP 1 LAST PACK_TYPE 0402LF
J 0
(-7825 6225);
DISPLAY 0.489362 (-7825 6225);
PAINT SKYBLUE (-7825 6225);
FORCEPROP 2 LAST CDS_LIB pure_quanta
J 0
(-8075 6225);
DISPLAY INVISIBLE (-8075 6225);
FORCEPROP 1 LAST PATH I275
J 0
(-8125 6375);
DISPLAY 0.978723 (-8125 6375);
PAINT WHITE (-8125 6375);
DISPLAY INVISIBLE (-8125 6375);
FORCEADD VCC_CORE..1
(-8500 6625);
FORCEPROP 3 LASTPIN (-8500 6575) SIG_NAME P3V3_STBY\g
J 0
(-8490 6585);
DISPLAY 0.659574 (-8490 6585);
PAINT MONO (-8490 6585);
DISPLAY INVISIBLE (-8490 6585);
FORCEPROP 1 LAST HDL_POWER P3V3_STBY
J 1
(-8500 6675);
DISPLAY 0.489362 (-8500 6675);
PAINT GREEN (-8500 6675);
FORCEPROP 2 LAST CDS_LIB pure_quanta_power
J 0
(-8500 6625);
DISPLAY INVISIBLE (-8500 6625);
FORCEPROP 1 LAST PATH I276
J 0
(-8450 6650);
DISPLAY 0.872340 (-8450 6650);
PAINT AQUA (-8450 6650);
DISPLAY INVISIBLE (-8450 6650);
FORCEADD Q_RES..1
(-8075 6375);
FORCEPROP 1 LAST LOCATION PR234
J 0
(-8275 6375);
DISPLAY 0.489362 (-8275 6375);
PAINT SKYBLUE (-8275 6375);
FORCEPROP 0 LAST $SEC 1
J 0
(-8125 6475);
DISPLAY 0.680851 (-8125 6475);
PAINT MONO (-8125 6475);
DISPLAY INVISIBLE (-8125 6475);
FORCEPROP 0 LAST CDS_SEC 1
J 0
(-8125 6475);
DISPLAY 1.021277 (-8125 6475);
DISPLAY INVISIBLE (-8125 6475);
FORCEPROP 1 LASTPIN (-8175 6375) $PN 1
J 0
(-8163 6387);
DISPLAY 0.489362 (-8163 6387);
PAINT MONO (-8163 6387);
FORCEPROP 1 LASTPIN (-7975 6375) $PN 2
J 0
(-8013 6387);
DISPLAY 0.489362 (-8013 6387);
PAINT MONO (-8013 6387);
FORCEPROP 1 LAST WATTAGE 1/16W
J 2
(-7700 6475);
DISPLAY 0.489362 (-7700 6475);
PAINT SKYBLUE (-7700 6475);
FORCEPROP 1 LAST MATERIAL CHIP
J 0
(-7950 6475);
DISPLAY 0.489362 (-7950 6475);
PAINT SKYBLUE (-7950 6475);
FORCEPROP 1 LAST TOLERANCE 5%
J 0
(-7900 6375);
DISPLAY 0.489362 (-7900 6375);
PAINT SKYBLUE (-7900 6375);
FORCEPROP 1 LAST VALUE 0
J 2
(-7925 6375);
DISPLAY 0.489362 (-7925 6375);
PAINT SKYBLUE (-7925 6375);
FORCEPROP 1 LAST PART_NUMBER CS00002JB38
J 0
(-7950 6425);
DISPLAY 0.489362 (-7950 6425);
PAINT SKYBLUE (-7950 6425);
FORCEPROP 1 LAST PACK_TYPE 0402LF
J 0
(-7825 6375);
DISPLAY 0.489362 (-7825 6375);
PAINT SKYBLUE (-7825 6375);
FORCEPROP 2 LAST CDS_LIB pure_quanta
J 0
(-8075 6375);
DISPLAY INVISIBLE (-8075 6375);
FORCEPROP 1 LAST PATH I277
J 0
(-8125 6525);
DISPLAY 0.978723 (-8125 6525);
PAINT WHITE (-8125 6525);
DISPLAY INVISIBLE (-8125 6525);
FORCEADD Q_RES..1
(-8075 6525);
FORCEPROP 1 LAST LOCATION PR233
J 0
(-8275 6525);
DISPLAY 0.489362 (-8275 6525);
PAINT SKYBLUE (-8275 6525);
FORCEPROP 0 LAST $SEC 1
J 0
(-8125 6625);
DISPLAY 0.680851 (-8125 6625);
PAINT MONO (-8125 6625);
DISPLAY INVISIBLE (-8125 6625);
FORCEPROP 0 LAST CDS_SEC 1
J 0
(-8125 6625);
DISPLAY 1.021277 (-8125 6625);
DISPLAY INVISIBLE (-8125 6625);
FORCEPROP 1 LASTPIN (-8175 6525) $PN 1
J 0
(-8163 6537);
DISPLAY 0.489362 (-8163 6537);
PAINT MONO (-8163 6537);
FORCEPROP 1 LASTPIN (-7975 6525) $PN 2
J 0
(-8013 6537);
DISPLAY 0.489362 (-8013 6537);
PAINT MONO (-8013 6537);
FORCEPROP 1 LAST WATTAGE 1/16W
J 2
(-7700 6625);
DISPLAY 0.489362 (-7700 6625);
PAINT SKYBLUE (-7700 6625);
FORCEPROP 1 LAST MATERIAL CHIP
J 0
(-7950 6625);
DISPLAY 0.489362 (-7950 6625);
PAINT SKYBLUE (-7950 6625);
FORCEPROP 1 LAST TOLERANCE 1%
J 0
(-7875 6525);
DISPLAY 0.489362 (-7875 6525);
PAINT SKYBLUE (-7875 6525);
FORCEPROP 1 LAST VALUE 1K
J 2
(-7900 6525);
DISPLAY 0.489362 (-7900 6525);
PAINT SKYBLUE (-7900 6525);
FORCEPROP 1 LAST PART_NUMBER TMP_QCS21002FB24
J 0
(-7950 6575);
DISPLAY 0.489362 (-7950 6575);
PAINT SKYBLUE (-7950 6575);
FORCEPROP 1 LAST PACK_TYPE 0402LF
J 0
(-7775 6525);
DISPLAY 0.489362 (-7775 6525);
PAINT SKYBLUE (-7775 6525);
FORCEPROP 2 LAST CDS_LIB pure_quanta
J 0
(-8075 6525);
DISPLAY INVISIBLE (-8075 6525);
FORCEPROP 1 LAST PATH I278
J 0
(-8125 6675);
DISPLAY 0.978723 (-8125 6675);
PAINT WHITE (-8125 6675);
DISPLAY INVISIBLE (-8125 6675);
FORCEADD Q_CAP..2
(-7225 6525);
FORCEPROP 1 LAST LOCATION PC360
J 1
(-7425 6525);
DISPLAY 0.489362 (-7425 6525);
PAINT SKYBLUE (-7425 6525);
FORCEPROP 0 LAST $SEC 1
J 0
(-7275 6625);
DISPLAY 0.680851 (-7275 6625);
PAINT MONO (-7275 6625);
DISPLAY INVISIBLE (-7275 6625);
FORCEPROP 0 LAST CDS_SEC 1
J 0
(-7275 6625);
DISPLAY 1.021277 (-7275 6625);
DISPLAY INVISIBLE (-7275 6625);
FORCEPROP 1 LASTPIN (-7325 6525) $PN 1
J 0
(-7335 6540);
DISPLAY 0.489362 (-7335 6540);
PAINT MONO (-7335 6540);
FORCEPROP 1 LASTPIN (-7125 6525) $PN 2
J 0
(-7140 6540);
DISPLAY 0.489362 (-7140 6540);
PAINT MONO (-7140 6540);
FORCEPROP 1 LAST MATERIAL EMPTY
J 0
(-6750 6525);
DISPLAY 0.489362 (-6750 6525);
PAINT RED (-6750 6525);
FORCEPROP 1 LAST TOLERANCE 5%
J 2
(-6575 6475);
DISPLAY 0.489362 (-6575 6475);
PAINT SKYBLUE (-6575 6475);
FORCEPROP 1 LAST VALUE 1000PF
J 2
(-6900 6525);
DISPLAY 0.489362 (-6900 6525);
PAINT SKYBLUE (-6900 6525);
FORCEPROP 1 LAST PART_NUMBER TMP_QCH21006JB10
J 1
(-6950 6475);
DISPLAY 0.489362 (-6950 6475);
PAINT SKYBLUE (-6950 6475);
FORCEPROP 1 LAST VOLTAGE 50V
J 0
(-6875 6525);
DISPLAY 0.489362 (-6875 6525);
PAINT SKYBLUE (-6875 6525);
FORCEPROP 1 LAST PACK_TYPE 0402
J 1
(-6725 6475);
DISPLAY 0.489362 (-6725 6475);
PAINT SKYBLUE (-6725 6475);
FORCEPROP 2 LAST CDS_LIB pure_quanta
J 0
(-7225 6525);
DISPLAY INVISIBLE (-7225 6525);
FORCEPROP 1 LAST PATH I279
J 0
(-7225 6725);
DISPLAY 0.978723 (-7225 6725);
PAINT WHITE (-7225 6725);
DISPLAY INVISIBLE (-7225 6725);
FORCEADD UNIVERSAL_GND..1
(-6650 450);
FORCEPROP 3 LASTPIN (-6650 500) SIG_NAME GND\g
J 0
(-6640 510);
DISPLAY 0.659574 (-6640 510);
PAINT MONO (-6640 510);
DISPLAY INVISIBLE (-6640 510);
FORCEPROP 2 LAST CDS_LIB pure_quanta_power
J 0
(-6650 450);
PAINT MONO (-6650 450);
DISPLAY INVISIBLE (-6650 450);
FORCEPROP 1 LAST PATH I280
J 0
(-6575 450);
DISPLAY 0.872340 (-6575 450);
PAINT AQUA (-6575 450);
DISPLAY INVISIBLE (-6575 450);
FORCEPROP 1 LAST HDL_POWER GND
J 1
(-6625 375);
DISPLAY 0.872340 (-6625 375);
PAINT GREEN (-6625 375);
DISPLAY INVISIBLE (-6625 375);
FORCEADD Q_CAP..1
(-6650 675);
FORCEPROP 1 LAST LOCATION PC364
J 0
(-6600 800);
DISPLAY 0.489362 (-6600 800);
PAINT SKYBLUE (-6600 800);
FORCEPROP 0 LAST $SEC 1
J 0
(-6600 850);
DISPLAY 0.680851 (-6600 850);
PAINT MONO (-6600 850);
DISPLAY INVISIBLE (-6600 850);
FORCEPROP 0 LAST CDS_SEC 1
J 0
(-6600 850);
DISPLAY 1.021277 (-6600 850);
DISPLAY INVISIBLE (-6600 850);
FORCEPROP 1 LASTPIN (-6650 775) $PN 1
J 0
(-6640 755);
DISPLAY 0.489362 (-6640 755);
PAINT MONO (-6640 755);
FORCEPROP 1 LASTPIN (-6650 575) $PN 2
J 0
(-6640 555);
DISPLAY 0.489362 (-6640 555);
PAINT MONO (-6640 555);
FORCEPROP 1 LAST MATERIAL X7R
J 0
(-6600 600);
DISPLAY 0.489362 (-6600 600);
PAINT SKYBLUE (-6600 600);
FORCEPROP 1 LAST TOLERANCE 10%
J 0
(-6600 650);
DISPLAY 0.489362 (-6600 650);
PAINT SKYBLUE (-6600 650);
FORCEPROP 1 LAST VALUE 0.1UF
J 0
(-6600 750);
DISPLAY 0.489362 (-6600 750);
PAINT SKYBLUE (-6600 750);
FORCEPROP 1 LAST PART_NUMBER CH4104K1B00
J 0
(-6600 500);
DISPLAY 0.489362 (-6600 500);
PAINT SKYBLUE (-6600 500);
FORCEPROP 1 LAST VOLTAGE 25V
J 0
(-6600 700);
DISPLAY 0.489362 (-6600 700);
PAINT SKYBLUE (-6600 700);
FORCEPROP 1 LAST PACK_TYPE 0402
J 0
(-6600 550);
DISPLAY 0.489362 (-6600 550);
PAINT SKYBLUE (-6600 550);
FORCEPROP 2 LAST CDS_LIB pure_quanta
J 0
(-6650 675);
DISPLAY INVISIBLE (-6650 675);
FORCEPROP 1 LAST PATH I281
J 0
(-6600 825);
DISPLAY 0.978723 (-6600 825);
PAINT WHITE (-6600 825);
DISPLAY INVISIBLE (-6600 825);
FORCEADD UNIVERSAL_GND..1
(-6450 700);
FORCEPROP 3 LASTPIN (-6450 750) SIG_NAME GND\g
J 0
(-6440 760);
DISPLAY 0.659574 (-6440 760);
PAINT MONO (-6440 760);
DISPLAY INVISIBLE (-6440 760);
FORCEPROP 2 LAST CDS_LIB pure_quanta_power
J 0
(-6450 700);
PAINT MONO (-6450 700);
DISPLAY INVISIBLE (-6450 700);
FORCEPROP 1 LAST PATH I282
J 0
(-6375 700);
DISPLAY 0.872340 (-6375 700);
PAINT AQUA (-6375 700);
DISPLAY INVISIBLE (-6375 700);
FORCEPROP 1 LAST HDL_POWER GND
J 1
(-6425 625);
DISPLAY 0.872340 (-6425 625);
PAINT GREEN (-6425 625);
DISPLAY INVISIBLE (-6425 625);
FORCEADD UNIVERSAL_GND..1
R 1
(-6475 1275);
FORCEPROP 3 LASTPIN (-6525 1275) SIG_NAME GND\g
J 0
(-6515 1285);
DISPLAY 0.659574 (-6515 1285);
PAINT MONO (-6515 1285);
DISPLAY INVISIBLE (-6515 1285);
FORCEPROP 2 LAST CDS_LIB pure_quanta_power
J 0
(-6475 1275);
PAINT MONO (-6475 1275);
DISPLAY INVISIBLE (-6475 1275);
FORCEPROP 1 LAST PATH I284
R 1
J 0
(-6475 1350);
DISPLAY 0.872340 (-6475 1350);
PAINT AQUA (-6475 1350);
DISPLAY INVISIBLE (-6475 1350);
FORCEPROP 1 LAST HDL_POWER GND
R 1
J 1
(-6400 1300);
DISPLAY 0.872340 (-6400 1300);
PAINT GREEN (-6400 1300);
DISPLAY INVISIBLE (-6400 1300);
FORCEADD UNIVERSAL_GND..1
(-4350 750);
FORCEPROP 3 LASTPIN (-4350 800) SIG_NAME GND\g
J 0
(-4340 810);
DISPLAY 0.659574 (-4340 810);
PAINT MONO (-4340 810);
DISPLAY INVISIBLE (-4340 810);
FORCEPROP 2 LAST CDS_LIB pure_quanta_power
J 0
(-4350 750);
PAINT MONO (-4350 750);
DISPLAY INVISIBLE (-4350 750);
FORCEPROP 1 LAST PATH I285
J 0
(-4275 750);
DISPLAY 0.872340 (-4275 750);
PAINT AQUA (-4275 750);
DISPLAY INVISIBLE (-4275 750);
FORCEPROP 1 LAST HDL_POWER GND
J 1
(-4325 675);
DISPLAY 0.872340 (-4325 675);
PAINT GREEN (-4325 675);
DISPLAY INVISIBLE (-4325 675);
FORCEADD Q_CAP..1
(-4350 1000);
FORCEPROP 1 LAST LOCATION PC368
J 0
(-4300 1100);
DISPLAY 0.489362 (-4300 1100);
PAINT SKYBLUE (-4300 1100);
FORCEPROP 0 LAST $SEC 1
J 0
(-4300 1150);
DISPLAY 0.680851 (-4300 1150);
PAINT MONO (-4300 1150);
DISPLAY INVISIBLE (-4300 1150);
FORCEPROP 0 LAST CDS_SEC 1
J 0
(-4300 1150);
DISPLAY 1.021277 (-4300 1150);
DISPLAY INVISIBLE (-4300 1150);
FORCEPROP 1 LASTPIN (-4350 1100) $PN 1
J 0
(-4340 1080);
DISPLAY 0.489362 (-4340 1080);
PAINT MONO (-4340 1080);
FORCEPROP 1 LASTPIN (-4350 900) $PN 2
J 0
(-4340 880);
DISPLAY 0.489362 (-4340 880);
PAINT MONO (-4340 880);
FORCEPROP 1 LAST VOLTAGE 50V
J 0
(-4300 1000);
DISPLAY 0.489362 (-4300 1000);
PAINT SKYBLUE (-4300 1000);
FORCEPROP 1 LAST MATERIAL X7R
J 0
(-4300 900);
DISPLAY 0.489362 (-4300 900);
PAINT SKYBLUE (-4300 900);
FORCEPROP 1 LAST TOLERANCE 10%
J 0
(-4300 950);
DISPLAY 0.489362 (-4300 950);
PAINT SKYBLUE (-4300 950);
FORCEPROP 1 LAST VALUE 470PF
J 0
(-4300 1050);
DISPLAY 0.489362 (-4300 1050);
PAINT SKYBLUE (-4300 1050);
FORCEPROP 1 LAST PART_NUMBER TMP_QCH14706KB18
J 0
(-4300 775);
DISPLAY 0.489362 (-4300 775);
PAINT SKYBLUE (-4300 775);
FORCEPROP 1 LAST PACK_TYPE 0402
J 0
(-4300 850);
DISPLAY 0.489362 (-4300 850);
PAINT SKYBLUE (-4300 850);
FORCEPROP 2 LAST CDS_LIB pure_quanta
J 0
(-4350 1000);
DISPLAY INVISIBLE (-4350 1000);
FORCEPROP 1 LAST PATH I286
J 0
(-4300 1150);
DISPLAY 0.978723 (-4300 1150);
PAINT WHITE (-4300 1150);
DISPLAY INVISIBLE (-4300 1150);
FORCEADD OFFPAGE..4
(-3750 1175);
FORCEPROP 2 LAST $XR2 196 
J 0
(-3324 1175);
DISPLAY 0.638298 (-3324 1175);
PAINT MONO (-3324 1175);
FORCEPROP 2 LAST $XR1 195 
J 0
(-3444 1175);
DISPLAY 0.638298 (-3444 1175);
PAINT MONO (-3444 1175);
FORCEPROP 2 LAST $XR0 194 
J 0
(-3564 1175);
DISPLAY 0.638298 (-3564 1175);
PAINT MONO (-3564 1175);
FORCEPROP 2 LAST CDS_LIB standard
J 0
(-3750 1175);
DISPLAY INVISIBLE (-3750 1175);
FORCEPROP 1 LAST OFFPAGE TRUE
J 0
(-3425 1050);
DISPLAY 0.872340 (-3425 1050);
PAINT GREEN (-3425 1050);
DISPLAY INVISIBLE (-3425 1050);
FORCEPROP 1 LAST COMMENT_BODY TRUE
J 0
(-3775 1075);
DISPLAY 0.872340 (-3775 1075);
PAINT GREEN (-3775 1075);
DISPLAY INVISIBLE (-3775 1075);
FORCEPROP 2 LAST PATH I291
J 0
(-2950 1225);
DISPLAY 1.021277 (-2950 1225);
DISPLAY INVISIBLE (-2950 1225);
FORCEADD UNIVERSAL_GND..1
R 1
(-6525 6100);
FORCEPROP 3 LASTPIN (-6575 6100) SIG_NAME GND\g
J 0
(-6565 6110);
DISPLAY 0.659574 (-6565 6110);
PAINT MONO (-6565 6110);
DISPLAY INVISIBLE (-6565 6110);
FORCEPROP 2 LAST CDS_LIB pure_quanta_power
J 0
(-6525 6100);
PAINT MONO (-6525 6100);
DISPLAY INVISIBLE (-6525 6100);
FORCEPROP 1 LAST PATH I311
R 1
J 0
(-6525 6175);
DISPLAY 0.872340 (-6525 6175);
PAINT AQUA (-6525 6175);
DISPLAY INVISIBLE (-6525 6175);
FORCEPROP 1 LAST HDL_POWER GND
R 1
J 1
(-6450 6125);
DISPLAY 0.872340 (-6450 6125);
PAINT GREEN (-6450 6125);
DISPLAY INVISIBLE (-6450 6125);
FORCEADD UNIVERSAL_GND..1
R 1
(-6525 6525);
FORCEPROP 3 LASTPIN (-6575 6525) SIG_NAME GND\g
J 0
(-6565 6535);
DISPLAY 0.659574 (-6565 6535);
PAINT MONO (-6565 6535);
DISPLAY INVISIBLE (-6565 6535);
FORCEPROP 2 LAST CDS_LIB pure_quanta_power
J 0
(-6525 6525);
PAINT MONO (-6525 6525);
DISPLAY INVISIBLE (-6525 6525);
FORCEPROP 1 LAST PATH I312
R 1
J 0
(-6525 6600);
DISPLAY 0.872340 (-6525 6600);
PAINT AQUA (-6525 6600);
DISPLAY INVISIBLE (-6525 6600);
FORCEPROP 1 LAST HDL_POWER GND
R 1
J 1
(-6450 6550);
DISPLAY 0.872340 (-6450 6550);
PAINT GREEN (-6450 6550);
DISPLAY INVISIBLE (-6450 6550);
FORCEADD Q_CAP..1
(-4350 5725);
FORCEPROP 1 LAST LOCATION PC366
J 0
(-4300 5850);
DISPLAY 0.489362 (-4300 5850);
PAINT SKYBLUE (-4300 5850);
FORCEPROP 2 LAST $SEC 1
J 0
(-4300 5925);
DISPLAY 0.680851 (-4300 5925);
PAINT MONO (-4300 5925);
DISPLAY INVISIBLE (-4300 5925);
FORCEPROP 2 LAST CDS_SEC 1
J 0
(-4300 5925);
DISPLAY 1.021277 (-4300 5925);
DISPLAY INVISIBLE (-4300 5925);
FORCEPROP 1 LASTPIN (-4350 5825) $PN 1
J 0
(-4340 5805);
DISPLAY 0.489362 (-4340 5805);
FORCEPROP 1 LASTPIN (-4350 5625) $PN 2
J 0
(-4340 5605);
DISPLAY 0.489362 (-4340 5605);
FORCEPROP 1 LAST MATERIAL X6S
J 0
(-4300 5650);
DISPLAY 0.489362 (-4300 5650);
PAINT SKYBLUE (-4300 5650);
FORCEPROP 1 LAST TOLERANCE 20%
J 0
(-4300 5700);
DISPLAY 0.489362 (-4300 5700);
PAINT SKYBLUE (-4300 5700);
FORCEPROP 1 LAST VALUE 10UF
J 0
(-4300 5800);
DISPLAY 0.489362 (-4300 5800);
PAINT SKYBLUE (-4300 5800);
FORCEPROP 1 LAST PART_NUMBER CH6101MEB01
J 0
(-4300 5550);
DISPLAY 0.489362 (-4300 5550);
PAINT SKYBLUE (-4300 5550);
FORCEPROP 1 LAST VOLTAGE 6.3V
J 0
(-4300 5750);
DISPLAY 0.489362 (-4300 5750);
PAINT SKYBLUE (-4300 5750);
FORCEPROP 1 LAST PACK_TYPE C0402
J 0
(-4300 5600);
DISPLAY 0.489362 (-4300 5600);
PAINT SKYBLUE (-4300 5600);
FORCEPROP 2 LAST CDS_LIB pure_quanta
J 0
(-4350 5725);
PAINT MONO (-4350 5725);
DISPLAY INVISIBLE (-4350 5725);
FORCEPROP 1 LAST PATH I319
J 0
(-4300 5875);
DISPLAY 0.978723 (-4300 5875);
PAINT WHITE (-4300 5875);
DISPLAY INVISIBLE (-4300 5875);
FORCEADD Q_CAP..1
(-4350 6200);
FORCEPROP 1 LAST LOCATION PC365
J 0
(-4300 6325);
DISPLAY 0.489362 (-4300 6325);
PAINT SKYBLUE (-4300 6325);
FORCEPROP 0 LAST $SEC 1
J 0
(-4300 6375);
DISPLAY 0.680851 (-4300 6375);
PAINT MONO (-4300 6375);
DISPLAY INVISIBLE (-4300 6375);
FORCEPROP 0 LAST CDS_SEC 1
J 0
(-4300 6375);
DISPLAY 1.021277 (-4300 6375);
DISPLAY INVISIBLE (-4300 6375);
FORCEPROP 1 LASTPIN (-4350 6300) $PN 1
J 0
(-4340 6280);
DISPLAY 0.489362 (-4340 6280);
PAINT MONO (-4340 6280);
FORCEPROP 1 LASTPIN (-4350 6100) $PN 2
J 0
(-4340 6080);
DISPLAY 0.489362 (-4340 6080);
PAINT MONO (-4340 6080);
FORCEPROP 1 LAST MATERIAL X6S
J 0
(-4300 6125);
DISPLAY 0.489362 (-4300 6125);
PAINT SKYBLUE (-4300 6125);
FORCEPROP 1 LAST TOLERANCE 10%
J 0
(-4300 6175);
DISPLAY 0.489362 (-4300 6175);
PAINT SKYBLUE (-4300 6175);
FORCEPROP 1 LAST VALUE 1UF
J 0
(-4300 6275);
DISPLAY 0.489362 (-4300 6275);
PAINT SKYBLUE (-4300 6275);
FORCEPROP 1 LAST PART_NUMBER CH5103KEB01
J 0
(-4300 6025);
DISPLAY 0.489362 (-4300 6025);
PAINT SKYBLUE (-4300 6025);
FORCEPROP 1 LAST VOLTAGE 16V
J 0
(-4300 6225);
DISPLAY 0.489362 (-4300 6225);
PAINT SKYBLUE (-4300 6225);
FORCEPROP 1 LAST PACK_TYPE C0402
J 0
(-4300 6075);
DISPLAY 0.489362 (-4300 6075);
PAINT SKYBLUE (-4300 6075);
FORCEPROP 2 LAST CDS_LIB pure_quanta
J 0
(-4350 6200);
DISPLAY INVISIBLE (-4350 6200);
FORCEPROP 1 LAST PATH I322
J 0
(-4300 6350);
DISPLAY 0.978723 (-4300 6350);
PAINT WHITE (-4300 6350);
DISPLAY INVISIBLE (-4300 6350);
FORCEADD Q_RES..1
(-3900 6375);
FORCEPROP 1 LAST LOCATION PR253
J 0
(-4125 6375);
DISPLAY 0.489362 (-4125 6375);
PAINT SKYBLUE (-4125 6375);
FORCEPROP 0 LAST $SEC 1
J 0
(-3950 6475);
DISPLAY 0.680851 (-3950 6475);
PAINT MONO (-3950 6475);
DISPLAY INVISIBLE (-3950 6475);
FORCEPROP 0 LAST CDS_SEC 1
J 0
(-3950 6475);
DISPLAY 1.021277 (-3950 6475);
DISPLAY INVISIBLE (-3950 6475);
FORCEPROP 1 LASTPIN (-4000 6375) $PN 1
J 0
(-3988 6387);
DISPLAY 0.489362 (-3988 6387);
PAINT MONO (-3988 6387);
FORCEPROP 1 LASTPIN (-3800 6375) $PN 2
J 0
(-3838 6387);
DISPLAY 0.489362 (-3838 6387);
PAINT MONO (-3838 6387);
FORCEPROP 1 LAST WATTAGE 1/16W
J 2
(-3450 6275);
DISPLAY 0.489362 (-3450 6275);
PAINT SKYBLUE (-3450 6275);
FORCEPROP 1 LAST MATERIAL CHIP
J 0
(-3600 6400);
DISPLAY 0.489362 (-3600 6400);
PAINT SKYBLUE (-3600 6400);
FORCEPROP 1 LAST TOLERANCE 1%
J 0
(-3700 6400);
DISPLAY 0.489362 (-3700 6400);
PAINT SKYBLUE (-3700 6400);
FORCEPROP 1 LAST VALUE 1
J 2
(-3725 6400);
DISPLAY 0.489362 (-3725 6400);
PAINT SKYBLUE (-3725 6400);
FORCEPROP 1 LAST PART_NUMBER CS-1002FB23
J 0
(-3750 6325);
DISPLAY 0.489362 (-3750 6325);
PAINT SKYBLUE (-3750 6325);
FORCEPROP 1 LAST PACK_TYPE 0402LF
J 0
(-3750 6275);
DISPLAY 0.489362 (-3750 6275);
PAINT SKYBLUE (-3750 6275);
FORCEPROP 2 LAST CDS_LIB pure_quanta
J 0
(-3900 6375);
DISPLAY INVISIBLE (-3900 6375);
FORCEPROP 1 LAST PATH I325
J 0
(-3950 6525);
DISPLAY 0.978723 (-3950 6525);
PAINT WHITE (-3950 6525);
DISPLAY INVISIBLE (-3950 6525);
FORCEADD VCC_CORE..1
(-3375 6500);
FORCEPROP 3 LASTPIN (-3375 6450) SIG_NAME P3V3_STBY\g
J 0
(-3365 6460);
DISPLAY 0.659574 (-3365 6460);
PAINT MONO (-3365 6460);
DISPLAY INVISIBLE (-3365 6460);
FORCEPROP 1 LAST HDL_POWER P3V3_STBY
J 1
(-3375 6550);
DISPLAY 0.489362 (-3375 6550);
PAINT GREEN (-3375 6550);
FORCEPROP 2 LAST CDS_LIB pure_quanta_power
J 0
(-3375 6500);
DISPLAY INVISIBLE (-3375 6500);
FORCEPROP 1 LAST PATH I326
J 0
(-3325 6525);
DISPLAY 0.872340 (-3325 6525);
PAINT AQUA (-3325 6525);
DISPLAY INVISIBLE (-3325 6525);
FORCEADD OFFPAGE..1
(-9950 4000);
FORCEPROP 2 LAST $XR1 200 
J 0
(-10351 4000);
DISPLAY 0.638298 (-10351 4000);
PAINT MONO (-10351 4000);
FORCEPROP 2 LAST $XR0 54 
J 0
(-10231 4000);
DISPLAY 0.638298 (-10231 4000);
PAINT MONO (-10231 4000);
FORCEPROP 2 LAST CDS_LIB standard
J 0
(-9950 4000);
DISPLAY INVISIBLE (-9950 4000);
FORCEPROP 1 LAST OFFPAGE TRUE
J 0
(-9625 3875);
DISPLAY 0.872340 (-9625 3875);
PAINT GREEN (-9625 3875);
DISPLAY INVISIBLE (-9625 3875);
FORCEPROP 1 LAST COMMENT_BODY TRUE
J 0
(-9825 3900);
DISPLAY 0.872340 (-9825 3900);
PAINT GREEN (-9825 3900);
DISPLAY INVISIBLE (-9825 3900);
FORCEPROP 2 LAST PATH I336
J 0
(-10225 4050);
DISPLAY 1.021277 (-10225 4050);
DISPLAY INVISIBLE (-10225 4050);
FORCEADD RAA229620GNPHA0..1
(-5675 3625);
FORCEPROP 1 LAST LOCATION PU34
J 0
(-6225 6650);
DISPLAY 0.489362 (-6225 6650);
PAINT SKYBLUE (-6225 6650);
FORCEPROP 0 LAST $SEC 1
J 0
(-6225 6675);
DISPLAY 0.680851 (-6225 6675);
PAINT MONO (-6225 6675);
DISPLAY INVISIBLE (-6225 6675);
FORCEPROP 0 LAST CDS_SEC 1
J 0
(-6225 6675);
DISPLAY 1.021277 (-6225 6675);
DISPLAY INVISIBLE (-6225 6675);
FORCEPROP 0 LASTPIN (-5025 1975) $PN 38
J 0
(-5015 1985);
DISPLAY 0.489362 (-5015 1985);
PAINT MONO (-5015 1985);
FORCEPROP 0 LASTPIN (-5025 2275) $PN 37
J 0
(-5015 2285);
DISPLAY 0.489362 (-5015 2285);
PAINT MONO (-5015 2285);
FORCEPROP 0 LASTPIN (-5025 2575) $PN 36
J 0
(-5015 2585);
DISPLAY 0.489362 (-5015 2585);
PAINT MONO (-5015 2585);
FORCEPROP 0 LASTPIN (-5025 2875) $PN 35
J 0
(-5015 2885);
DISPLAY 0.489362 (-5015 2885);
PAINT MONO (-5015 2885);
FORCEPROP 0 LASTPIN (-5025 3175) $PN 34
J 0
(-5015 3185);
DISPLAY 0.489362 (-5015 3185);
PAINT MONO (-5015 3185);
FORCEPROP 0 LASTPIN (-5025 3475) $PN 33
J 0
(-5015 3485);
DISPLAY 0.489362 (-5015 3485);
PAINT MONO (-5015 3485);
FORCEPROP 0 LASTPIN (-5025 3775) $PN 32
J 0
(-5015 3785);
DISPLAY 0.489362 (-5015 3785);
PAINT MONO (-5015 3785);
FORCEPROP 0 LASTPIN (-5025 4075) $PN 31
J 0
(-5015 4085);
DISPLAY 0.489362 (-5015 4085);
PAINT MONO (-5015 4085);
FORCEPROP 0 LASTPIN (-5025 4375) $PN 30
J 0
(-5015 4385);
DISPLAY 0.489362 (-5015 4385);
PAINT MONO (-5015 4385);
FORCEPROP 0 LASTPIN (-5025 4675) $PN 29
J 0
(-5015 4685);
DISPLAY 0.489362 (-5015 4685);
PAINT MONO (-5015 4685);
FORCEPROP 0 LASTPIN (-5025 4975) $PN 28
J 0
(-5015 4985);
DISPLAY 0.489362 (-5015 4985);
PAINT MONO (-5015 4985);
FORCEPROP 0 LASTPIN (-5025 5275) $PN 27
J 0
(-5015 5285);
DISPLAY 0.489362 (-5015 5285);
PAINT MONO (-5015 5285);
FORCEPROP 0 LASTPIN (-6375 6225) $PN 17
J 2
(-6385 6235);
DISPLAY 0.489362 (-6385 6235);
PAINT MONO (-6385 6235);
FORCEPROP 0 LASTPIN (-6375 1625) $PN 42
J 2
(-6385 1635);
DISPLAY 0.489362 (-6385 1635);
PAINT MONO (-6385 1635);
FORCEPROP 0 LASTPIN (-6375 4925) $PN 15
J 2
(-6385 4935);
DISPLAY 0.489362 (-6385 4935);
PAINT MONO (-6385 4935);
FORCEPROP 0 LASTPIN (-6375 2375) $PN 41
J 2
(-6385 2385);
DISPLAY 0.489362 (-6385 2385);
PAINT MONO (-6385 2385);
FORCEPROP 0 LASTPIN (-6375 6375) $PN 16
J 2
(-6385 6385);
DISPLAY 0.489362 (-6385 6385);
PAINT MONO (-6385 6385);
FORCEPROP 0 LASTPIN (-6375 1125) $PN 20
J 2
(-6385 1135);
DISPLAY 0.489362 (-6385 1135);
PAINT MONO (-6385 1135);
FORCEPROP 0 LASTPIN (-6375 5225) $PN 14
J 2
(-6385 5235);
DISPLAY 0.489362 (-6385 5235);
PAINT MONO (-6385 5235);
FORCEPROP 0 LASTPIN (-6375 5075) $PN 13
J 2
(-6385 5085);
DISPLAY 0.489362 (-6385 5085);
PAINT MONO (-6385 5085);
FORCEPROP 0 LASTPIN (-5025 2075) $PN 1
J 0
(-5015 2085);
DISPLAY 0.489362 (-5015 2085);
PAINT MONO (-5015 2085);
FORCEPROP 0 LASTPIN (-5025 2375) $PN 2
J 0
(-5015 2385);
DISPLAY 0.489362 (-5015 2385);
PAINT MONO (-5015 2385);
FORCEPROP 0 LASTPIN (-5025 2675) $PN 3
J 0
(-5015 2685);
DISPLAY 0.489362 (-5015 2685);
PAINT MONO (-5015 2685);
FORCEPROP 0 LASTPIN (-5025 2975) $PN 4
J 0
(-5015 2985);
DISPLAY 0.489362 (-5015 2985);
PAINT MONO (-5015 2985);
FORCEPROP 0 LASTPIN (-5025 3275) $PN 5
J 0
(-5015 3285);
DISPLAY 0.489362 (-5015 3285);
PAINT MONO (-5015 3285);
FORCEPROP 0 LASTPIN (-5025 3575) $PN 6
J 0
(-5015 3585);
DISPLAY 0.489362 (-5015 3585);
PAINT MONO (-5015 3585);
FORCEPROP 0 LASTPIN (-5025 3875) $PN 7
J 0
(-5015 3885);
DISPLAY 0.489362 (-5015 3885);
PAINT MONO (-5015 3885);
FORCEPROP 0 LASTPIN (-5025 4175) $PN 8
J 0
(-5015 4185);
DISPLAY 0.489362 (-5015 4185);
PAINT MONO (-5015 4185);
FORCEPROP 0 LASTPIN (-5025 4475) $PN 9
J 0
(-5015 4485);
DISPLAY 0.489362 (-5015 4485);
PAINT MONO (-5015 4485);
FORCEPROP 0 LASTPIN (-5025 4775) $PN 10
J 0
(-5015 4785);
DISPLAY 0.489362 (-5015 4785);
PAINT MONO (-5015 4785);
FORCEPROP 0 LASTPIN (-5025 5075) $PN 11
J 0
(-5015 5085);
DISPLAY 0.489362 (-5015 5085);
PAINT MONO (-5015 5085);
FORCEPROP 0 LASTPIN (-5025 5375) $PN 12
J 0
(-5015 5385);
DISPLAY 0.489362 (-5015 5385);
PAINT MONO (-5015 5385);
FORCEPROP 0 LASTPIN (-6375 2525) $PN 18
J 2
(-6385 2535);
DISPLAY 0.489362 (-6385 2535);
PAINT MONO (-6385 2535);
FORCEPROP 0 LASTPIN (-6375 4075) $PN 26
J 2
(-6385 4085);
DISPLAY 0.489362 (-6385 4085);
PAINT MONO (-6385 4085);
FORCEPROP 0 LASTPIN (-6375 2975) $PN 39
J 2
(-6385 2985);
DISPLAY 0.489362 (-6385 2985);
PAINT MONO (-6385 2985);
FORCEPROP 0 LASTPIN (-6375 5925) $PN 22
J 2
(-6385 5935);
DISPLAY 0.489362 (-6385 5935);
PAINT MONO (-6385 5935);
FORCEPROP 0 LASTPIN (-6375 5775) $PN 21
J 2
(-6385 5785);
DISPLAY 0.489362 (-6385 5785);
PAINT MONO (-6385 5785);
FORCEPROP 0 LASTPIN (-6375 5475) $PN 24
J 2
(-6385 5485);
DISPLAY 0.489362 (-6385 5485);
PAINT MONO (-6385 5485);
FORCEPROP 0 LASTPIN (-6375 5625) $PN 23
J 2
(-6385 5635);
DISPLAY 0.489362 (-6385 5635);
PAINT MONO (-6385 5635);
FORCEPROP 0 LASTPIN (-5025 1175) $PN 44
J 0
(-5015 1185);
DISPLAY 0.489362 (-5015 1185);
PAINT MONO (-5015 1185);
FORCEPROP 0 LASTPIN (-5025 1475) $PN 43
J 0
(-5015 1485);
DISPLAY 0.489362 (-5015 1485);
PAINT MONO (-5015 1485);
FORCEPROP 0 LASTPIN (-6375 825) $PN TH
J 2
(-6385 835);
DISPLAY 0.489362 (-6385 835);
PAINT MONO (-6385 835);
FORCEPROP 0 LASTPIN (-5025 6375) $PN 47
J 0
(-5015 6385);
DISPLAY 0.489362 (-5015 6385);
PAINT MONO (-5015 6385);
FORCEPROP 0 LASTPIN (-5025 6075) $PN 48
J 0
(-5015 6085);
DISPLAY 0.489362 (-5015 6085);
PAINT MONO (-5015 6085);
FORCEPROP 0 LASTPIN (-6375 2125) $PN 19
J 2
(-6385 2135);
DISPLAY 0.489362 (-6385 2135);
PAINT MONO (-6385 2135);
FORCEPROP 0 LASTPIN (-6375 925) $PN 46
J 2
(-6385 935);
DISPLAY 0.489362 (-6385 935);
PAINT MONO (-6385 935);
FORCEPROP 0 LASTPIN (-6375 1025) $PN 45
J 2
(-6385 1035);
DISPLAY 0.489362 (-6385 1035);
PAINT MONO (-6385 1035);
FORCEPROP 0 LASTPIN (-6375 4325) $PN 25
J 2
(-6385 4335);
DISPLAY 0.489362 (-6385 4335);
PAINT MONO (-6385 4335);
FORCEPROP 0 LASTPIN (-6375 3225) $PN 40
J 2
(-6385 3235);
DISPLAY 0.489362 (-6385 3235);
PAINT MONO (-6385 3235);
FORCEPROP 2 LAST VALUE RAA229620GNP#HA0
J 0
(-5875 6500);
DISPLAY 0.489362 (-5875 6500);
PAINT SKYBLUE (-5875 6500);
FORCEPROP 1 LAST PART_NUMBER AR0T6GPV005
J 0
(-6225 6575);
DISPLAY 0.489362 (-6225 6575);
PAINT SKYBLUE (-6225 6575);
FORCEPROP 1 LAST MATERIAL IC
J 0
(-6225 6500);
DISPLAY 0.489362 (-6225 6500);
PAINT SKYBLUE (-6225 6500);
FORCEPROP 2 LAST PART_TYPE SMLF
J 0
(-5875 6550);
DISPLAY 0.638298 (-5875 6550);
FORCEPROP 1 LAST PATH I339
J 0
(-5675 3625);
DISPLAY 0.723404 (-5675 3625);
PAINT GREEN (-5675 3625);
DISPLAY INVISIBLE (-5675 3625);
FORCEPROP 2 LAST CDS_LIB pure_quanta
J 0
(-5675 3625);
DISPLAY INVISIBLE (-5675 3625);
FORCEPROP 1 LAST CDS_LMAN_SYM_OUTLINE -550,2850,500,-2850
J 0
(-5675 3625);
DISPLAY 0.468085 (-5675 3625);
PAINT GREEN (-5675 3625);
DISPLAY INVISIBLE (-5675 3625);
FORCEPROP 1 LAST NEEDS_NO_SIZE TRUE
J 0
(-5675 3625);
DISPLAY 0.723404 (-5675 3625);
PAINT GREEN (-5675 3625);
DISPLAY INVISIBLE (-5675 3625);
FORCEADD OFFPAGE..2
(-3675 5900);
FORCEPROP 2 LAST $XR4 199 
J 0
(-3006 5900);
DISPLAY 0.638298 (-3006 5900);
PAINT MONO (-3006 5900);
FORCEPROP 2 LAST $XR3 198 
J 0
(-3126 5900);
DISPLAY 0.638298 (-3126 5900);
PAINT MONO (-3126 5900);
FORCEPROP 2 LAST $XR2 196 
J 0
(-3246 5900);
DISPLAY 0.638298 (-3246 5900);
PAINT MONO (-3246 5900);
FORCEPROP 2 LAST $XR1 195 
J 0
(-3366 5900);
DISPLAY 0.638298 (-3366 5900);
PAINT MONO (-3366 5900);
FORCEPROP 2 LAST $XR0 194 
J 0
(-3486 5900);
DISPLAY 0.638298 (-3486 5900);
PAINT MONO (-3486 5900);
FORCEPROP 2 LAST CDS_LIB standard
J 0
(-3675 5900);
DISPLAY INVISIBLE (-3675 5900);
FORCEPROP 1 LAST OFFPAGE TRUE
J 0
(-3350 5775);
DISPLAY 0.872340 (-3350 5775);
PAINT GREEN (-3350 5775);
DISPLAY INVISIBLE (-3350 5775);
FORCEPROP 1 LAST COMMENT_BODY TRUE
J 0
(-3720 5805);
DISPLAY 0.872340 (-3720 5805);
PAINT GREEN (-3720 5805);
DISPLAY INVISIBLE (-3720 5805);
FORCEPROP 2 LAST PATH I340
J 0
(-3500 5975);
DISPLAY 1.021277 (-3500 5975);
DISPLAY INVISIBLE (-3500 5975);
FORCEADD Q_RES..1
(-8075 5625);
FORCEPROP 1 LAST LOCATION PR238
J 0
(-8125 5675);
DISPLAY 0.489362 (-8125 5675);
PAINT SKYBLUE (-8125 5675);
FORCEPROP 0 LAST $SEC 1
J 0
(-7675 5750);
DISPLAY 0.680851 (-7675 5750);
PAINT MONO (-7675 5750);
DISPLAY INVISIBLE (-7675 5750);
FORCEPROP 0 LAST CDS_SEC 1
J 0
(-7675 5750);
DISPLAY 1.021277 (-7675 5750);
DISPLAY INVISIBLE (-7675 5750);
FORCEPROP 1 LASTPIN (-8175 5625) $PN 1
J 0
(-8163 5637);
DISPLAY 0.489362 (-8163 5637);
PAINT MONO (-8163 5637);
FORCEPROP 1 LASTPIN (-7975 5625) $PN 2
J 0
(-8013 5637);
DISPLAY 0.489362 (-8013 5637);
PAINT MONO (-8013 5637);
FORCEPROP 1 LAST WATTAGE 1/16W
J 2
(-7675 5725);
DISPLAY 0.489362 (-7675 5725);
PAINT SKYBLUE (-7675 5725);
FORCEPROP 1 LAST MATERIAL CHIP
J 0
(-7950 5725);
DISPLAY 0.489362 (-7950 5725);
PAINT SKYBLUE (-7950 5725);
FORCEPROP 1 LAST TOLERANCE 5%
J 0
(-7525 5675);
DISPLAY 0.489362 (-7525 5675);
PAINT SKYBLUE (-7525 5675);
FORCEPROP 1 LAST VALUE 0
J 2
(-7550 5675);
DISPLAY 0.489362 (-7550 5675);
PAINT SKYBLUE (-7550 5675);
FORCEPROP 1 LAST PART_NUMBER CS00002JB38
J 0
(-7950 5675);
DISPLAY 0.489362 (-7950 5675);
PAINT SKYBLUE (-7950 5675);
FORCEPROP 1 LAST PACK_TYPE 0402LF
J 0
(-7450 5675);
DISPLAY 0.489362 (-7450 5675);
PAINT SKYBLUE (-7450 5675);
FORCEPROP 2 LAST CDS_LIB pure_quanta
J 0
(-8075 5625);
DISPLAY INVISIBLE (-8075 5625);
FORCEPROP 1 LAST PATH I348
J 0
(-8125 5775);
DISPLAY 0.978723 (-8125 5775);
PAINT WHITE (-8125 5775);
DISPLAY INVISIBLE (-8125 5775);
FORCEADD Q_RES..1
(-8075 5475);
FORCEPROP 1 LAST LOCATION PR239
J 0
(-8125 5525);
DISPLAY 0.489362 (-8125 5525);
PAINT SKYBLUE (-8125 5525);
FORCEPROP 0 LAST $SEC 1
J 0
(-7675 5600);
DISPLAY 0.680851 (-7675 5600);
PAINT MONO (-7675 5600);
DISPLAY INVISIBLE (-7675 5600);
FORCEPROP 0 LAST CDS_SEC 1
J 0
(-7675 5600);
DISPLAY 1.021277 (-7675 5600);
DISPLAY INVISIBLE (-7675 5600);
FORCEPROP 1 LASTPIN (-8175 5475) $PN 1
J 0
(-8163 5487);
DISPLAY 0.489362 (-8163 5487);
PAINT MONO (-8163 5487);
FORCEPROP 1 LASTPIN (-7975 5475) $PN 2
J 0
(-8013 5487);
DISPLAY 0.489362 (-8013 5487);
PAINT MONO (-8013 5487);
FORCEPROP 1 LAST WATTAGE 1/16W
J 2
(-7675 5575);
DISPLAY 0.489362 (-7675 5575);
PAINT SKYBLUE (-7675 5575);
FORCEPROP 1 LAST MATERIAL CHIP
J 0
(-7950 5575);
DISPLAY 0.489362 (-7950 5575);
PAINT SKYBLUE (-7950 5575);
FORCEPROP 1 LAST TOLERANCE 5%
J 0
(-7550 5525);
DISPLAY 0.489362 (-7550 5525);
PAINT SKYBLUE (-7550 5525);
FORCEPROP 1 LAST VALUE 0
J 2
(-7575 5525);
DISPLAY 0.489362 (-7575 5525);
PAINT SKYBLUE (-7575 5525);
FORCEPROP 1 LAST PART_NUMBER CS00002JB38
J 0
(-7950 5525);
DISPLAY 0.489362 (-7950 5525);
PAINT SKYBLUE (-7950 5525);
FORCEPROP 1 LAST PACK_TYPE 0402LF
J 0
(-7475 5525);
DISPLAY 0.489362 (-7475 5525);
PAINT SKYBLUE (-7475 5525);
FORCEPROP 2 LAST CDS_LIB pure_quanta
J 0
(-8075 5475);
DISPLAY INVISIBLE (-8075 5475);
FORCEPROP 1 LAST PATH I351
J 0
(-8125 5625);
DISPLAY 0.978723 (-8125 5625);
PAINT WHITE (-8125 5625);
DISPLAY INVISIBLE (-8125 5625);
FORCEADD OFFPAGE..5
(-10225 5625);
FORCEPROP 2 LAST $XR0 54 
J 0
(-10449 5625);
DISPLAY 0.638298 (-10449 5625);
PAINT MONO (-10449 5625);
FORCEPROP 2 LAST CDS_LIB standard
J 0
(-10225 5625);
DISPLAY INVISIBLE (-10225 5625);
FORCEPROP 1 LAST OFFPAGE TRUE
J 0
(-9900 5500);
DISPLAY 0.872340 (-9900 5500);
PAINT GREEN (-9900 5500);
DISPLAY INVISIBLE (-9900 5500);
FORCEPROP 1 LAST COMMENT_BODY TRUE
J 0
(-10125 5550);
DISPLAY 0.872340 (-10125 5550);
PAINT GREEN (-10125 5550);
DISPLAY INVISIBLE (-10125 5550);
FORCEPROP 2 LAST PATH I355
J 0
(-10175 5700);
DISPLAY 1.021277 (-10175 5700);
DISPLAY INVISIBLE (-10175 5700);
FORCEADD Q_RES..1
(-7375 5075);
FORCEPROP 1 LAST LOCATION PR249
J 0
(-7575 5075);
DISPLAY 0.489362 (-7575 5075);
PAINT SKYBLUE (-7575 5075);
FORCEPROP 0 LAST $SEC 1
J 0
(-7575 5100);
DISPLAY 0.680851 (-7575 5100);
PAINT MONO (-7575 5100);
DISPLAY INVISIBLE (-7575 5100);
FORCEPROP 0 LAST CDS_SEC 1
J 0
(-7575 5100);
DISPLAY 1.021277 (-7575 5100);
DISPLAY INVISIBLE (-7575 5100);
FORCEPROP 1 LASTPIN (-7475 5075) $PN 1
J 0
(-7463 5087);
DISPLAY 0.489362 (-7463 5087);
PAINT MONO (-7463 5087);
FORCEPROP 1 LASTPIN (-7275 5075) $PN 2
J 0
(-7313 5087);
DISPLAY 0.489362 (-7313 5087);
PAINT MONO (-7313 5087);
FORCEPROP 1 LAST WATTAGE 1/16W
J 2
(-7450 5025);
DISPLAY 0.489362 (-7450 5025);
PAINT SKYBLUE (-7450 5025);
FORCEPROP 1 LAST MATERIAL CHIP
J 0
(-7700 5025);
DISPLAY 0.489362 (-7700 5025);
PAINT SKYBLUE (-7700 5025);
FORCEPROP 1 LAST TOLERANCE 5%
J 0
(-7350 5025);
DISPLAY 0.489362 (-7350 5025);
PAINT SKYBLUE (-7350 5025);
FORCEPROP 1 LAST VALUE 0
J 2
(-7375 5025);
DISPLAY 0.489362 (-7375 5025);
PAINT SKYBLUE (-7375 5025);
FORCEPROP 1 LAST PART_NUMBER CS00002JB38
J 0
(-8050 5025);
DISPLAY 0.489362 (-8050 5025);
PAINT SKYBLUE (-8050 5025);
FORCEPROP 1 LAST PACK_TYPE 0402LF
J 0
(-7275 5025);
DISPLAY 0.489362 (-7275 5025);
PAINT SKYBLUE (-7275 5025);
FORCEPROP 2 LAST CDS_LIB pure_quanta
J 0
(-7375 5075);
DISPLAY INVISIBLE (-7375 5075);
FORCEPROP 1 LAST PATH I366
J 0
(-7425 5225);
DISPLAY 0.978723 (-7425 5225);
PAINT WHITE (-7425 5225);
DISPLAY INVISIBLE (-7425 5225);
FORCEADD Q_RES..1
(-7375 4925);
FORCEPROP 1 LAST LOCATION PR250
J 0
(-7575 4925);
DISPLAY 0.489362 (-7575 4925);
PAINT SKYBLUE (-7575 4925);
FORCEPROP 0 LAST $SEC 1
J 0
(-7575 4950);
DISPLAY 0.680851 (-7575 4950);
PAINT MONO (-7575 4950);
DISPLAY INVISIBLE (-7575 4950);
FORCEPROP 0 LAST CDS_SEC 1
J 0
(-7575 4950);
DISPLAY 1.021277 (-7575 4950);
DISPLAY INVISIBLE (-7575 4950);
FORCEPROP 1 LASTPIN (-7475 4925) $PN 1
J 0
(-7463 4937);
DISPLAY 0.489362 (-7463 4937);
PAINT MONO (-7463 4937);
FORCEPROP 1 LASTPIN (-7275 4925) $PN 2
J 0
(-7313 4937);
DISPLAY 0.489362 (-7313 4937);
PAINT MONO (-7313 4937);
FORCEPROP 1 LAST WATTAGE 1/16W
J 2
(-7450 4875);
DISPLAY 0.489362 (-7450 4875);
PAINT SKYBLUE (-7450 4875);
FORCEPROP 1 LAST MATERIAL CHIP
J 0
(-7700 4875);
DISPLAY 0.489362 (-7700 4875);
PAINT SKYBLUE (-7700 4875);
FORCEPROP 1 LAST TOLERANCE 5%
J 0
(-7350 4875);
DISPLAY 0.489362 (-7350 4875);
PAINT SKYBLUE (-7350 4875);
FORCEPROP 1 LAST VALUE 0
J 2
(-7375 4875);
DISPLAY 0.489362 (-7375 4875);
PAINT SKYBLUE (-7375 4875);
FORCEPROP 1 LAST PART_NUMBER CS00002JB38
J 0
(-8050 4875);
DISPLAY 0.489362 (-8050 4875);
PAINT SKYBLUE (-8050 4875);
FORCEPROP 1 LAST PACK_TYPE 0402LF
J 0
(-7275 4875);
DISPLAY 0.489362 (-7275 4875);
PAINT SKYBLUE (-7275 4875);
FORCEPROP 2 LAST CDS_LIB pure_quanta
J 0
(-7375 4925);
DISPLAY INVISIBLE (-7375 4925);
FORCEPROP 1 LAST PATH I367
J 0
(-7425 5075);
DISPLAY 0.978723 (-7425 5075);
PAINT WHITE (-7425 5075);
DISPLAY INVISIBLE (-7425 5075);
FORCEADD OFFPAGE..5
(-8350 4925);
FORCEPROP 2 LAST $XR1 81 
J 0
(-8664 4925);
DISPLAY 0.638298 (-8664 4925);
PAINT MONO (-8664 4925);
FORCEPROP 2 LAST $XR0 82 
J 0
(-8574 4925);
DISPLAY 0.638298 (-8574 4925);
PAINT MONO (-8574 4925);
FORCEPROP 2 LAST CDS_LIB standard
J 0
(-8350 4925);
DISPLAY INVISIBLE (-8350 4925);
FORCEPROP 1 LAST OFFPAGE TRUE
J 0
(-8025 4800);
DISPLAY 0.872340 (-8025 4800);
PAINT GREEN (-8025 4800);
DISPLAY INVISIBLE (-8025 4800);
FORCEPROP 1 LAST COMMENT_BODY TRUE
J 0
(-8250 4850);
DISPLAY 0.872340 (-8250 4850);
PAINT GREEN (-8250 4850);
DISPLAY INVISIBLE (-8250 4850);
FORCEPROP 2 LAST PATH I368
J 0
(-8300 5000);
DISPLAY 1.021277 (-8300 5000);
DISPLAY INVISIBLE (-8300 5000);
FORCEADD OFFPAGE..5
(-8075 2375);
FORCEPROP 2 LAST $XR0 81 
J 0
(-8329 2375);
DISPLAY 0.638298 (-8329 2375);
PAINT MONO (-8329 2375);
FORCEPROP 2 LAST CDS_LIB standard
J 0
(-8075 2375);
DISPLAY INVISIBLE (-8075 2375);
FORCEPROP 1 LAST OFFPAGE TRUE
J 0
(-7750 2250);
DISPLAY 0.872340 (-7750 2250);
PAINT GREEN (-7750 2250);
DISPLAY INVISIBLE (-7750 2250);
FORCEPROP 1 LAST COMMENT_BODY TRUE
J 0
(-7975 2300);
DISPLAY 0.872340 (-7975 2300);
PAINT GREEN (-7975 2300);
DISPLAY INVISIBLE (-7975 2300);
FORCEPROP 2 LAST PATH I371
J 0
(-8025 2450);
DISPLAY 1.021277 (-8025 2450);
DISPLAY INVISIBLE (-8025 2450);
FORCEADD Q_RES..1
(-7400 2375);
FORCEPROP 1 LAST LOCATION PR241
J 0
(-7450 2425);
DISPLAY 0.489362 (-7450 2425);
PAINT SKYBLUE (-7450 2425);
FORCEPROP 0 LAST $SEC 1
J 0
(-7450 2450);
DISPLAY 0.680851 (-7450 2450);
PAINT MONO (-7450 2450);
DISPLAY INVISIBLE (-7450 2450);
FORCEPROP 0 LAST CDS_SEC 1
J 0
(-7450 2450);
DISPLAY 1.021277 (-7450 2450);
DISPLAY INVISIBLE (-7450 2450);
FORCEPROP 1 LASTPIN (-7500 2375) $PN 1
J 0
(-7488 2387);
DISPLAY 0.489362 (-7488 2387);
PAINT MONO (-7488 2387);
FORCEPROP 1 LASTPIN (-7300 2375) $PN 2
J 0
(-7338 2387);
DISPLAY 0.489362 (-7338 2387);
PAINT MONO (-7338 2387);
FORCEPROP 1 LAST PART_NUMBER CS00002JB38
J 0
(-8075 2325);
DISPLAY 0.489362 (-8075 2325);
PAINT SKYBLUE (-8075 2325);
FORCEPROP 1 LAST WATTAGE 1/16W
J 2
(-7475 2325);
DISPLAY 0.489362 (-7475 2325);
PAINT SKYBLUE (-7475 2325);
FORCEPROP 1 LAST MATERIAL CHIP
J 0
(-7725 2325);
DISPLAY 0.489362 (-7725 2325);
PAINT SKYBLUE (-7725 2325);
FORCEPROP 1 LAST TOLERANCE 5%
J 0
(-7375 2325);
DISPLAY 0.489362 (-7375 2325);
PAINT SKYBLUE (-7375 2325);
FORCEPROP 1 LAST VALUE 0
J 2
(-7400 2325);
DISPLAY 0.489362 (-7400 2325);
PAINT SKYBLUE (-7400 2325);
FORCEPROP 1 LAST PACK_TYPE 0402LF
J 0
(-7300 2325);
DISPLAY 0.489362 (-7300 2325);
PAINT SKYBLUE (-7300 2325);
FORCEPROP 2 LAST CDS_LIB pure_quanta
J 0
(-7400 2375);
DISPLAY INVISIBLE (-7400 2375);
FORCEPROP 1 LAST PATH I372
J 0
(-7450 2525);
DISPLAY 0.978723 (-7450 2525);
PAINT WHITE (-7450 2525);
DISPLAY INVISIBLE (-7450 2525);
FORCEADD Q_RES..1
(-7425 2675);
FORCEPROP 1 LAST LOCATION PR247
J 0
(-7800 2700);
DISPLAY 0.489362 (-7800 2700);
PAINT SKYBLUE (-7800 2700);
FORCEPROP 0 LAST $SEC 1
J 0
(-7675 2775);
DISPLAY 0.680851 (-7675 2775);
PAINT MONO (-7675 2775);
DISPLAY INVISIBLE (-7675 2775);
FORCEPROP 0 LAST CDS_SEC 1
J 0
(-7675 2775);
DISPLAY 1.021277 (-7675 2775);
DISPLAY INVISIBLE (-7675 2775);
FORCEPROP 1 LASTPIN (-7525 2675) $PN 1
J 0
(-7513 2687);
DISPLAY 0.489362 (-7513 2687);
PAINT MONO (-7513 2687);
FORCEPROP 1 LASTPIN (-7325 2675) $PN 2
J 0
(-7363 2687);
DISPLAY 0.489362 (-7363 2687);
PAINT MONO (-7363 2687);
FORCEPROP 1 LAST WATTAGE 1/16W
J 2
(-7150 2700);
DISPLAY 0.489362 (-7150 2700);
PAINT SKYBLUE (-7150 2700);
FORCEPROP 1 LAST MATERIAL CHIP
J 0
(-7375 2700);
DISPLAY 0.489362 (-7375 2700);
PAINT SKYBLUE (-7375 2700);
FORCEPROP 1 LAST TOLERANCE 1%
J 0
(-7600 2700);
DISPLAY 0.489362 (-7600 2700);
PAINT SKYBLUE (-7600 2700);
FORCEPROP 1 LAST VALUE 1K
J 2
(-7625 2700);
DISPLAY 0.489362 (-7625 2700);
PAINT SKYBLUE (-7625 2700);
FORCEPROP 1 LAST PART_NUMBER TMP_QCS21002FB24
J 0
(-7675 2750);
DISPLAY 0.489362 (-7675 2750);
PAINT SKYBLUE (-7675 2750);
FORCEPROP 1 LAST PACK_TYPE 0402LF
J 0
(-7525 2700);
DISPLAY 0.489362 (-7525 2700);
PAINT SKYBLUE (-7525 2700);
FORCEPROP 2 LAST CDS_LIB pure_quanta
J 0
(-7425 2675);
DISPLAY INVISIBLE (-7425 2675);
FORCEPROP 1 LAST PATH I378
J 0
(-7475 2825);
DISPLAY 0.978723 (-7475 2825);
PAINT WHITE (-7475 2825);
DISPLAY INVISIBLE (-7475 2825);
FORCEADD Q_RES..1
(-7400 2525);
FORCEPROP 1 LAST LOCATION PR240
J 0
(-7450 2575);
DISPLAY 0.489362 (-7450 2575);
PAINT SKYBLUE (-7450 2575);
FORCEPROP 0 LAST $SEC 1
J 0
(-7450 2600);
DISPLAY 0.680851 (-7450 2600);
PAINT MONO (-7450 2600);
DISPLAY INVISIBLE (-7450 2600);
FORCEPROP 0 LAST CDS_SEC 1
J 0
(-7450 2600);
DISPLAY 1.021277 (-7450 2600);
DISPLAY INVISIBLE (-7450 2600);
FORCEPROP 1 LASTPIN (-7500 2525) $PN 1
J 0
(-7488 2537);
DISPLAY 0.489362 (-7488 2537);
PAINT MONO (-7488 2537);
FORCEPROP 1 LASTPIN (-7300 2525) $PN 2
J 0
(-7338 2537);
DISPLAY 0.489362 (-7338 2537);
PAINT MONO (-7338 2537);
FORCEPROP 1 LAST PART_NUMBER CS00002JB38
J 0
(-8075 2475);
DISPLAY 0.489362 (-8075 2475);
PAINT SKYBLUE (-8075 2475);
FORCEPROP 1 LAST WATTAGE 1/16W
J 2
(-7475 2475);
DISPLAY 0.489362 (-7475 2475);
PAINT SKYBLUE (-7475 2475);
FORCEPROP 1 LAST MATERIAL CHIP
J 0
(-7725 2475);
DISPLAY 0.489362 (-7725 2475);
PAINT SKYBLUE (-7725 2475);
FORCEPROP 1 LAST TOLERANCE 5%
J 0
(-7375 2475);
DISPLAY 0.489362 (-7375 2475);
PAINT SKYBLUE (-7375 2475);
FORCEPROP 1 LAST VALUE 0
J 2
(-7400 2475);
DISPLAY 0.489362 (-7400 2475);
PAINT SKYBLUE (-7400 2475);
FORCEPROP 1 LAST PACK_TYPE 0402LF
J 0
(-7300 2475);
DISPLAY 0.489362 (-7300 2475);
PAINT SKYBLUE (-7300 2475);
FORCEPROP 2 LAST CDS_LIB pure_quanta
J 0
(-7400 2525);
DISPLAY INVISIBLE (-7400 2525);
FORCEPROP 1 LAST PATH I379
J 0
(-7450 2675);
DISPLAY 0.978723 (-7450 2675);
PAINT WHITE (-7450 2675);
DISPLAY INVISIBLE (-7450 2675);
FORCEADD Q_CAP..2
(-7025 2000);
FORCEPROP 1 LAST LOCATION PC363
J 1
(-7350 2050);
DISPLAY 0.489362 (-7350 2050);
PAINT SKYBLUE (-7350 2050);
FORCEPROP 0 LAST $SEC 1
J 0
(-6450 2075);
DISPLAY 0.680851 (-6450 2075);
PAINT MONO (-6450 2075);
DISPLAY INVISIBLE (-6450 2075);
FORCEPROP 0 LAST CDS_SEC 1
J 0
(-6450 2075);
DISPLAY 1.021277 (-6450 2075);
DISPLAY INVISIBLE (-6450 2075);
FORCEPROP 1 LASTPIN (-7125 2000) $PN 1
J 0
(-7135 2015);
DISPLAY 0.489362 (-7135 2015);
PAINT MONO (-7135 2015);
FORCEPROP 1 LASTPIN (-6925 2000) $PN 2
J 0
(-6940 2015);
DISPLAY 0.489362 (-6940 2015);
PAINT MONO (-6940 2015);
FORCEPROP 1 LAST MATERIAL X7R
J 0
(-7050 2050);
DISPLAY 0.489362 (-7050 2050);
PAINT SKYBLUE (-7050 2050);
FORCEPROP 1 LAST TOLERANCE 10%
J 2
(-6450 2050);
DISPLAY 0.489362 (-6450 2050);
PAINT SKYBLUE (-6450 2050);
FORCEPROP 1 LAST VALUE 1UF
J 2
(-7225 2050);
DISPLAY 0.489362 (-7225 2050);
PAINT SKYBLUE (-7225 2050);
FORCEPROP 1 LAST PART_NUMBER CH5101K1B01
J 1
(-6800 2050);
DISPLAY 0.489362 (-6800 2050);
PAINT SKYBLUE (-6800 2050);
FORCEPROP 1 LAST VOLTAGE 6.3V
J 0
(-7175 2050);
DISPLAY 0.489362 (-7175 2050);
PAINT SKYBLUE (-7175 2050);
FORCEPROP 1 LAST PACK_TYPE 0402
J 1
(-6600 2050);
DISPLAY 0.489362 (-6600 2050);
PAINT SKYBLUE (-6600 2050);
FORCEPROP 2 LAST CDS_LIB pure_quanta
J 0
(-7025 2000);
DISPLAY INVISIBLE (-7025 2000);
FORCEPROP 1 LAST PATH I380
J 0
(-7025 2200);
DISPLAY 0.978723 (-7025 2200);
PAINT WHITE (-7025 2200);
DISPLAY INVISIBLE (-7025 2200);
FORCEADD UNIVERSAL_GND..1
R 1
(-6625 2000);
FORCEPROP 3 LASTPIN (-6675 2000) SIG_NAME GND\g
J 0
(-6665 2010);
DISPLAY 0.659574 (-6665 2010);
PAINT MONO (-6665 2010);
DISPLAY INVISIBLE (-6665 2010);
FORCEPROP 2 LAST CDS_LIB pure_quanta_power
J 0
(-6625 2000);
DISPLAY INVISIBLE (-6625 2000);
FORCEPROP 1 LAST PATH I381
R 1
J 0
(-6625 2075);
DISPLAY 0.872340 (-6625 2075);
PAINT AQUA (-6625 2075);
DISPLAY INVISIBLE (-6625 2075);
FORCEPROP 1 LAST HDL_POWER GND
R 1
J 1
(-6550 2025);
DISPLAY 0.872340 (-6550 2025);
PAINT GREEN (-6550 2025);
DISPLAY INVISIBLE (-6550 2025);
FORCEADD VCC_CORE..1
(-7575 2075);
FORCEPROP 3 LASTPIN (-7575 2025) SIG_NAME PVDD18_S5_P1\g
J 0
(-7565 2035);
DISPLAY 0.659574 (-7565 2035);
PAINT MONO (-7565 2035);
DISPLAY INVISIBLE (-7565 2035);
FORCEPROP 1 LAST HDL_POWER PVDD18_S5_P1
J 1
(-7575 2125);
DISPLAY 0.489362 (-7575 2125);
PAINT GREEN (-7575 2125);
FORCEPROP 2 LAST CDS_LIB pure_quanta_power
J 0
(-7575 2075);
DISPLAY INVISIBLE (-7575 2075);
FORCEPROP 1 LAST PATH I382
J 0
(-7525 2100);
DISPLAY 0.872340 (-7525 2100);
PAINT AQUA (-7525 2100);
DISPLAY INVISIBLE (-7525 2100);
FORCEADD OFFPAGE..1
(-8075 2525);
FORCEPROP 2 LAST $XR0 77 
J 0
(-8296 2525);
DISPLAY 0.638298 (-8296 2525);
PAINT MONO (-8296 2525);
FORCEPROP 2 LAST CDS_LIB standard
J 0
(-8075 2525);
DISPLAY INVISIBLE (-8075 2525);
FORCEPROP 1 LAST OFFPAGE TRUE
J 0
(-7750 2400);
DISPLAY 0.872340 (-7750 2400);
PAINT GREEN (-7750 2400);
DISPLAY INVISIBLE (-7750 2400);
FORCEPROP 1 LAST COMMENT_BODY TRUE
J 0
(-7950 2425);
DISPLAY 0.872340 (-7950 2425);
PAINT GREEN (-7950 2425);
DISPLAY INVISIBLE (-7950 2425);
FORCEPROP 2 LAST PATH I384
J 0
(-8025 2600);
DISPLAY 1.021277 (-8025 2600);
DISPLAY INVISIBLE (-8025 2600);
FORCEADD Q_RES..1
(-6750 2250);
FORCEPROP 1 LAST LOCATION PR252
J 0
(-6800 2200);
DISPLAY 0.489362 (-6800 2200);
PAINT SKYBLUE (-6800 2200);
FORCEPROP 0 LAST $SEC 1
J 0
(-7000 2350);
DISPLAY 0.680851 (-7000 2350);
PAINT MONO (-7000 2350);
DISPLAY INVISIBLE (-7000 2350);
FORCEPROP 0 LAST CDS_SEC 1
J 0
(-7000 2350);
DISPLAY 1.021277 (-7000 2350);
DISPLAY INVISIBLE (-7000 2350);
FORCEPROP 1 LASTPIN (-6850 2250) $PN 1
J 0
(-6838 2262);
DISPLAY 0.489362 (-6838 2262);
PAINT MONO (-6838 2262);
FORCEPROP 1 LASTPIN (-6650 2250) $PN 2
J 0
(-6688 2262);
DISPLAY 0.489362 (-6688 2262);
PAINT MONO (-6688 2262);
FORCEPROP 1 LAST WATTAGE 1/16W
J 2
(-6475 2275);
DISPLAY 0.489362 (-6475 2275);
PAINT SKYBLUE (-6475 2275);
FORCEPROP 1 LAST MATERIAL CHIP
J 0
(-6700 2275);
DISPLAY 0.489362 (-6700 2275);
PAINT SKYBLUE (-6700 2275);
FORCEPROP 1 LAST TOLERANCE 1%
J 0
(-6925 2275);
DISPLAY 0.489362 (-6925 2275);
PAINT SKYBLUE (-6925 2275);
FORCEPROP 1 LAST VALUE 1K
J 2
(-6950 2275);
DISPLAY 0.489362 (-6950 2275);
PAINT SKYBLUE (-6950 2275);
FORCEPROP 1 LAST PART_NUMBER TMP_QCS21002FB24
J 0
(-7000 2325);
DISPLAY 0.489362 (-7000 2325);
PAINT SKYBLUE (-7000 2325);
FORCEPROP 1 LAST PACK_TYPE 0402LF
J 0
(-6850 2275);
DISPLAY 0.489362 (-6850 2275);
PAINT SKYBLUE (-6850 2275);
FORCEPROP 2 LAST CDS_LIB pure_quanta
J 0
(-6750 2250);
DISPLAY INVISIBLE (-6750 2250);
FORCEPROP 1 LAST PATH I385
J 0
(-6800 2400);
DISPLAY 0.978723 (-6800 2400);
PAINT WHITE (-6800 2400);
DISPLAY INVISIBLE (-6800 2400);
FORCEADD VCC_CORE..1
(-9200 2650);
FORCEPROP 3 LASTPIN (-9200 2600) SIG_NAME P3V3_STBY\g
J 0
(-9190 2610);
DISPLAY 0.659574 (-9190 2610);
PAINT MONO (-9190 2610);
DISPLAY INVISIBLE (-9190 2610);
FORCEPROP 1 LAST HDL_POWER P3V3_STBY
J 1
(-9200 2700);
DISPLAY 0.489362 (-9200 2700);
PAINT GREEN (-9200 2700);
FORCEPROP 2 LAST CDS_LIB pure_quanta_power
J 0
(-9200 2650);
DISPLAY INVISIBLE (-9200 2650);
FORCEPROP 1 LAST PATH I390
J 0
(-9150 2675);
DISPLAY 0.872340 (-9150 2675);
PAINT AQUA (-9150 2675);
DISPLAY INVISIBLE (-9150 2675);
FORCEADD MOSFET_N..1
(-9250 1825);
FORCEPROP 1 LAST LOCATION PQ16
J 0
(-9125 1850);
DISPLAY 0.489362 (-9125 1850);
PAINT SKYBLUE (-9125 1850);
FORCEPROP 0 LAST $SEC 1
J 0
(-9100 1875);
DISPLAY 0.680851 (-9100 1875);
PAINT MONO (-9100 1875);
DISPLAY INVISIBLE (-9100 1875);
FORCEPROP 0 LAST CDS_SEC 1
J 0
(-9100 1875);
DISPLAY 1.021277 (-9100 1875);
DISPLAY INVISIBLE (-9100 1875);
FORCEPROP 1 LASTPIN (-9200 1925) $PN D
R 1
J 0
(-9200 1918);
DISPLAY 0.489362 (-9200 1918);
PAINT MONO (-9200 1918);
FORCEPROP 1 LASTPIN (-9350 1725) $PN G
J 2
(-9340 1728);
DISPLAY 0.489362 (-9340 1728);
PAINT MONO (-9340 1728);
FORCEPROP 1 LASTPIN (-9200 1625) $PN S
R 1
J 2
(-9200 1638);
DISPLAY 0.489362 (-9200 1638);
PAINT MONO (-9200 1638);
FORCEPROP 1 LAST MATERIAL IC
J 0
(-9125 1700);
DISPLAY 0.489362 (-9125 1700);
PAINT SKYBLUE (-9125 1700);
FORCEPROP 1 LAST VALUE BSS138K
J 0
(-9125 1800);
DISPLAY 0.489362 (-9125 1800);
PAINT SKYBLUE (-9125 1800);
FORCEPROP 1 LAST PART_NUMBER BAM138K0000
J 0
(-9125 1750);
DISPLAY 0.489362 (-9125 1750);
PAINT SKYBLUE (-9125 1750);
FORCEPROP 2 LAST CDS_LIB pure_quanta
J 0
(-9250 1825);
DISPLAY INVISIBLE (-9250 1825);
FORCEPROP 1 LAST CDS_LMAN_SYM_OUTLINE -50,50,100,-150
J 0
(-9250 1825);
DISPLAY 0.468085 (-9250 1825);
PAINT GREEN (-9250 1825);
DISPLAY INVISIBLE (-9250 1825);
FORCEPROP 0 LAST MANUF_PN BSS138K
J 0
(-9075 1700);
DISPLAY 1.021277 (-9075 1700);
DISPLAY INVISIBLE (-9075 1700);
FORCEPROP 0 LAST PATH I391
J 0
(-9075 1750);
DISPLAY 1.021277 (-9075 1750);
DISPLAY INVISIBLE (-9075 1750);
FORCEPROP 1 LAST PACK_TYPE SMLF
J 0
(-9225 1575);
DISPLAY 0.723404 (-9225 1575);
PAINT SKYBLUE (-9225 1575);
DISPLAY INVISIBLE (-9225 1575);
FORCEADD Q_RES..2
(-9200 2400);
FORCEPROP 1 LAST LOCATION PR232
J 0
(-9150 2525);
DISPLAY 0.489362 (-9150 2525);
PAINT SKYBLUE (-9150 2525);
FORCEPROP 0 LAST $SEC 1
J 0
(-9150 2550);
DISPLAY 0.680851 (-9150 2550);
PAINT MONO (-9150 2550);
DISPLAY INVISIBLE (-9150 2550);
FORCEPROP 0 LAST CDS_SEC 1
J 0
(-9450 2500);
DISPLAY 1.021277 (-9450 2500);
DISPLAY INVISIBLE (-9450 2500);
FORCEPROP 1 LASTPIN (-9200 2500) $PN 1
J 0
(-9195 2462);
DISPLAY 0.489362 (-9195 2462);
PAINT MONO (-9195 2462);
FORCEPROP 1 LASTPIN (-9200 2300) $PN 2
J 0
(-9195 2310);
DISPLAY 0.489362 (-9195 2310);
PAINT MONO (-9195 2310);
FORCEPROP 1 LAST WATTAGE 1/16W
J 0
(-9150 2375);
DISPLAY 0.489362 (-9150 2375);
PAINT SKYBLUE (-9150 2375);
FORCEPROP 1 LAST MATERIAL CHIP
J 0
(-9150 2325);
DISPLAY 0.489362 (-9150 2325);
PAINT SKYBLUE (-9150 2325);
FORCEPROP 1 LAST TOLERANCE 1%
J 0
(-9150 2425);
DISPLAY 0.489362 (-9150 2425);
PAINT SKYBLUE (-9150 2425);
FORCEPROP 1 LAST VALUE 1K
J 0
(-9150 2475);
DISPLAY 0.489362 (-9150 2475);
PAINT SKYBLUE (-9150 2475);
FORCEPROP 1 LAST PACK_TYPE 0402LF
J 0
(-9150 2275);
DISPLAY 0.489362 (-9150 2275);
PAINT SKYBLUE (-9150 2275);
FORCEPROP 2 LAST CDS_LIB pure_quanta
J 0
(-9200 2400);
DISPLAY INVISIBLE (-9200 2400);
FORCEPROP 1 LAST PATH I392
J 0
(-9150 2575);
DISPLAY 0.978723 (-9150 2575);
PAINT WHITE (-9150 2575);
DISPLAY INVISIBLE (-9150 2575);
FORCEPROP 1 LAST PART_NUMBER TMP_QCS21002FB24
J 0
(-9160 2275);
DISPLAY 0.489362 (-9160 2275);
PAINT SKYBLUE (-9160 2275);
DISPLAY INVISIBLE (-9160 2275);
FORCEADD UNIVERSAL_GND..1
(-9200 1425);
FORCEPROP 3 LASTPIN (-9200 1475) SIG_NAME GND\g
J 0
(-9190 1485);
DISPLAY 0.659574 (-9190 1485);
PAINT MONO (-9190 1485);
DISPLAY INVISIBLE (-9190 1485);
FORCEPROP 2 LAST CDS_LIB pure_quanta_power
J 0
(-9200 1425);
DISPLAY INVISIBLE (-9200 1425);
FORCEPROP 1 LAST PATH I393
J 0
(-9125 1425);
DISPLAY 0.872340 (-9125 1425);
PAINT AQUA (-9125 1425);
DISPLAY INVISIBLE (-9125 1425);
FORCEPROP 1 LAST HDL_POWER GND
J 1
(-9175 1350);
DISPLAY 0.872340 (-9175 1350);
PAINT GREEN (-9175 1350);
DISPLAY INVISIBLE (-9175 1350);
FORCEADD Q_RES..2
(-8500 1675);
FORCEPROP 1 LAST LOCATION PR244
J 0
(-8450 1725);
DISPLAY 0.489362 (-8450 1725);
PAINT SKYBLUE (-8450 1725);
FORCEPROP 0 LAST $SEC 1
J 0
(-8475 1750);
DISPLAY 0.680851 (-8475 1750);
PAINT MONO (-8475 1750);
DISPLAY INVISIBLE (-8475 1750);
FORCEPROP 0 LAST CDS_SEC 1
J 0
(-8475 1750);
DISPLAY 1.021277 (-8475 1750);
DISPLAY INVISIBLE (-8475 1750);
FORCEPROP 1 LASTPIN (-8500 1775) $PN 1
J 0
(-8495 1737);
DISPLAY 0.489362 (-8495 1737);
PAINT MONO (-8495 1737);
FORCEPROP 1 LASTPIN (-8500 1575) $PN 2
J 0
(-8495 1585);
DISPLAY 0.489362 (-8495 1585);
PAINT MONO (-8495 1585);
FORCEPROP 1 LAST PART_NUMBER TMP_QCS29532FB10
J 0
(-8450 1600);
DISPLAY 0.489362 (-8450 1600);
PAINT SKYBLUE (-8450 1600);
FORCEPROP 1 LAST PACK_TYPE 0402LF 
J 0
(-8450 1575);
DISPLAY 0.489362 (-8450 1575);
PAINT SKYBLUE (-8450 1575);
FORCEPROP 1 LAST WATTAGE 1/16W 
J 0
(-8450 1650);
DISPLAY 0.489362 (-8450 1650);
PAINT SKYBLUE (-8450 1650);
FORCEPROP 1 LAST MATERIAL CHIP
J 0
(-8450 1625);
DISPLAY 0.489362 (-8450 1625);
PAINT SKYBLUE (-8450 1625);
FORCEPROP 1 LAST TOLERANCE 1%
J 0
(-8450 1675);
DISPLAY 0.489362 (-8450 1675);
PAINT SKYBLUE (-8450 1675);
FORCEPROP 1 LAST VALUE 9.53K
J 0
(-8450 1700);
DISPLAY 0.489362 (-8450 1700);
PAINT SKYBLUE (-8450 1700);
FORCEPROP 2 LAST CDS_LIB pure_quanta
J 0
(-8500 1675);
DISPLAY INVISIBLE (-8500 1675);
FORCEPROP 1 LAST PATH I394
J 0
(-8450 1850);
DISPLAY 0.978723 (-8450 1850);
PAINT WHITE (-8450 1850);
DISPLAY INVISIBLE (-8450 1850);
FORCEADD Q_RES..1
(-9900 1725);
FORCEPROP 1 LAST LOCATION PR224
J 0
(-9950 1775);
DISPLAY 0.489362 (-9950 1775);
PAINT SKYBLUE (-9950 1775);
FORCEPROP 0 LAST $SEC 1
J 0
(-9550 1875);
DISPLAY 0.680851 (-9550 1875);
PAINT MONO (-9550 1875);
DISPLAY INVISIBLE (-9550 1875);
FORCEPROP 0 LAST CDS_SEC 1
J 0
(-9550 1875);
DISPLAY 1.021277 (-9550 1875);
DISPLAY INVISIBLE (-9550 1875);
FORCEPROP 1 LASTPIN (-10000 1725) $PN 1
J 0
(-9988 1737);
DISPLAY 0.489362 (-9988 1737);
PAINT MONO (-9988 1737);
FORCEPROP 1 LASTPIN (-9800 1725) $PN 2
J 0
(-9838 1737);
DISPLAY 0.489362 (-9838 1737);
PAINT MONO (-9838 1737);
FORCEPROP 1 LAST VALUE 0
J 2
(-10000 1575);
DISPLAY 0.489362 (-10000 1575);
PAINT SKYBLUE (-10000 1575);
FORCEPROP 1 LAST PART_NUMBER CS00002JB38
J 0
(-10025 1625);
DISPLAY 0.489362 (-10025 1625);
PAINT SKYBLUE (-10025 1625);
FORCEPROP 1 LAST WATTAGE 1/16W
J 2
(-9775 1675);
DISPLAY 0.489362 (-9775 1675);
PAINT SKYBLUE (-9775 1675);
FORCEPROP 1 LAST MATERIAL CHIP
J 0
(-10025 1675);
DISPLAY 0.489362 (-10025 1675);
PAINT SKYBLUE (-10025 1675);
FORCEPROP 1 LAST TOLERANCE 5%
J 0
(-9975 1575);
DISPLAY 0.489362 (-9975 1575);
PAINT SKYBLUE (-9975 1575);
FORCEPROP 1 LAST PACK_TYPE 0402LF
J 0
(-9900 1575);
DISPLAY 0.489362 (-9900 1575);
PAINT SKYBLUE (-9900 1575);
FORCEPROP 2 LAST CDS_LIB pure_quanta
J 0
(-9900 1725);
DISPLAY INVISIBLE (-9900 1725);
FORCEPROP 1 LAST PATH I395
J 0
(-9950 1875);
DISPLAY 0.978723 (-9950 1875);
PAINT WHITE (-9950 1875);
DISPLAY INVISIBLE (-9950 1875);
FORCEADD OFFPAGE..1
(-10400 1725);
FORCEPROP 2 LAST $XR0 80 
J 0
(-10681 1725);
DISPLAY 0.638298 (-10681 1725);
PAINT MONO (-10681 1725);
FORCEPROP 2 LAST CDS_LIB standard
J 0
(-10400 1725);
DISPLAY INVISIBLE (-10400 1725);
FORCEPROP 1 LAST OFFPAGE TRUE
J 0
(-10075 1600);
DISPLAY 0.872340 (-10075 1600);
PAINT GREEN (-10075 1600);
DISPLAY INVISIBLE (-10075 1600);
FORCEPROP 1 LAST COMMENT_BODY TRUE
J 0
(-10275 1625);
DISPLAY 0.872340 (-10275 1625);
PAINT GREEN (-10275 1625);
DISPLAY INVISIBLE (-10275 1625);
FORCEPROP 2 LAST PATH I396
J 0
(-10350 1800);
DISPLAY 1.021277 (-10350 1800);
DISPLAY INVISIBLE (-10350 1800);
FORCEADD Q_CAP..1
(-9700 1550);
FORCEPROP 1 LAST LOCATION PC356
J 0
(-9650 1650);
DISPLAY 0.489362 (-9650 1650);
PAINT SKYBLUE (-9650 1650);
FORCEPROP 0 LAST $SEC 1
J 0
(-9650 1675);
DISPLAY 0.680851 (-9650 1675);
PAINT MONO (-9650 1675);
DISPLAY INVISIBLE (-9650 1675);
FORCEPROP 0 LAST CDS_SEC 1
J 0
(-9650 1675);
DISPLAY 1.021277 (-9650 1675);
DISPLAY INVISIBLE (-9650 1675);
FORCEPROP 1 LASTPIN (-9700 1650) $PN 1
J 0
(-9690 1630);
DISPLAY 0.489362 (-9690 1630);
PAINT MONO (-9690 1630);
FORCEPROP 1 LASTPIN (-9700 1450) $PN 2
J 0
(-9690 1430);
DISPLAY 0.489362 (-9690 1430);
PAINT MONO (-9690 1430);
FORCEPROP 1 LAST MATERIAL X7R
J 0
(-9650 1450);
DISPLAY 0.489362 (-9650 1450);
PAINT SKYBLUE (-9650 1450);
FORCEPROP 1 LAST TOLERANCE 5%
J 0
(-9650 1500);
DISPLAY 0.489362 (-9650 1500);
PAINT SKYBLUE (-9650 1500);
FORCEPROP 1 LAST VALUE 1000PF
J 0
(-9650 1600);
DISPLAY 0.489362 (-9650 1600);
PAINT SKYBLUE (-9650 1600);
FORCEPROP 1 LAST PART_NUMBER TMP_QCH21006JB10
J 0
(-9650 1350);
DISPLAY 0.489362 (-9650 1350);
PAINT SKYBLUE (-9650 1350);
FORCEPROP 1 LAST VOLTAGE 50V
J 0
(-9650 1550);
DISPLAY 0.489362 (-9650 1550);
PAINT SKYBLUE (-9650 1550);
FORCEPROP 1 LAST PACK_TYPE 0402
J 0
(-9650 1400);
DISPLAY 0.489362 (-9650 1400);
PAINT SKYBLUE (-9650 1400);
FORCEPROP 2 LAST CDS_LIB pure_quanta
J 0
(-9700 1550);
DISPLAY INVISIBLE (-9700 1550);
FORCEPROP 1 LAST PATH I397
J 0
(-9650 1700);
DISPLAY 0.978723 (-9650 1700);
PAINT WHITE (-9650 1700);
DISPLAY INVISIBLE (-9650 1700);
FORCEADD UNIVERSAL_GND..1
(-9700 1300);
FORCEPROP 3 LASTPIN (-9700 1350) SIG_NAME GND\g
J 0
(-9690 1360);
DISPLAY 0.659574 (-9690 1360);
PAINT MONO (-9690 1360);
DISPLAY INVISIBLE (-9690 1360);
FORCEPROP 2 LAST CDS_LIB pure_quanta_power
J 0
(-9700 1300);
DISPLAY INVISIBLE (-9700 1300);
FORCEPROP 1 LAST PATH I398
J 0
(-9625 1300);
DISPLAY 0.872340 (-9625 1300);
PAINT AQUA (-9625 1300);
DISPLAY INVISIBLE (-9625 1300);
FORCEPROP 1 LAST HDL_POWER GND
J 1
(-9675 1225);
DISPLAY 0.872340 (-9675 1225);
PAINT GREEN (-9675 1225);
DISPLAY INVISIBLE (-9675 1225);
FORCEADD VCC_CORE..1
(-8925 1075);
FORCEPROP 3 LASTPIN (-8925 1025) SIG_NAME P5V_STBY\g
J 0
(-8915 1035);
DISPLAY 0.659574 (-8915 1035);
PAINT MONO (-8915 1035);
DISPLAY INVISIBLE (-8915 1035);
FORCEPROP 1 LAST HDL_POWER P5V_STBY
J 1
(-8925 1125);
DISPLAY 0.489362 (-8925 1125);
PAINT GREEN (-8925 1125);
FORCEPROP 2 LAST CDS_LIB pure_quanta_power
J 0
(-8925 1075);
DISPLAY INVISIBLE (-8925 1075);
FORCEPROP 1 LAST PATH I399
J 0
(-8875 1100);
DISPLAY 0.872340 (-8875 1100);
PAINT AQUA (-8875 1100);
DISPLAY INVISIBLE (-8875 1100);
FORCEADD Q_CAP..1
(-4350 1575);
FORCEPROP 1 LAST LOCATION PC367
J 0
(-4300 1675);
DISPLAY 0.489362 (-4300 1675);
PAINT SKYBLUE (-4300 1675);
FORCEPROP 0 LAST $SEC 1
J 0
(-4300 1700);
DISPLAY 0.680851 (-4300 1700);
PAINT MONO (-4300 1700);
DISPLAY INVISIBLE (-4300 1700);
FORCEPROP 0 LAST CDS_SEC 1
J 0
(-4300 1700);
DISPLAY 1.021277 (-4300 1700);
DISPLAY INVISIBLE (-4300 1700);
FORCEPROP 1 LASTPIN (-4350 1675) $PN 1
J 0
(-4340 1655);
DISPLAY 0.489362 (-4340 1655);
PAINT MONO (-4340 1655);
FORCEPROP 1 LASTPIN (-4350 1475) $PN 2
J 0
(-4340 1455);
DISPLAY 0.489362 (-4340 1455);
PAINT MONO (-4340 1455);
FORCEPROP 1 LAST MATERIAL X7R
J 0
(-4300 1475);
DISPLAY 0.489362 (-4300 1475);
PAINT SKYBLUE (-4300 1475);
FORCEPROP 1 LAST TOLERANCE 10%
J 0
(-4300 1525);
DISPLAY 0.489362 (-4300 1525);
PAINT SKYBLUE (-4300 1525);
FORCEPROP 1 LAST VALUE 470PF
J 0
(-4300 1625);
DISPLAY 0.489362 (-4300 1625);
PAINT SKYBLUE (-4300 1625);
FORCEPROP 1 LAST PART_NUMBER TMP_QCH14706KB18
J 0
(-4300 1350);
DISPLAY 0.489362 (-4300 1350);
PAINT SKYBLUE (-4300 1350);
FORCEPROP 1 LAST VOLTAGE 50V
J 0
(-4300 1575);
DISPLAY 0.489362 (-4300 1575);
PAINT SKYBLUE (-4300 1575);
FORCEPROP 1 LAST PACK_TYPE 0402
J 0
(-4300 1425);
DISPLAY 0.489362 (-4300 1425);
PAINT SKYBLUE (-4300 1425);
FORCEPROP 2 LAST CDS_LIB pure_quanta
J 0
(-4350 1575);
DISPLAY INVISIBLE (-4350 1575);
FORCEPROP 1 LAST PATH I400
J 0
(-4300 1725);
DISPLAY 0.978723 (-4300 1725);
PAINT WHITE (-4300 1725);
DISPLAY INVISIBLE (-4300 1725);
FORCEADD UNIVERSAL_GND..1
(-4350 1325);
FORCEPROP 3 LASTPIN (-4350 1375) SIG_NAME GND\g
J 0
(-4340 1385);
DISPLAY 0.659574 (-4340 1385);
PAINT MONO (-4340 1385);
DISPLAY INVISIBLE (-4340 1385);
FORCEPROP 2 LAST CDS_LIB pure_quanta_power
J 0
(-4350 1325);
DISPLAY INVISIBLE (-4350 1325);
FORCEPROP 1 LAST PATH I401
J 0
(-4275 1325);
DISPLAY 0.872340 (-4275 1325);
PAINT AQUA (-4275 1325);
DISPLAY INVISIBLE (-4275 1325);
FORCEPROP 1 LAST HDL_POWER GND
J 1
(-4325 1250);
DISPLAY 0.872340 (-4325 1250);
PAINT GREEN (-4325 1250);
DISPLAY INVISIBLE (-4325 1250);
FORCEADD OFFPAGE..4
(-3750 1775);
FORCEPROP 2 LAST $XR1 199 
J 0
(-3444 1775);
DISPLAY 0.638298 (-3444 1775);
PAINT MONO (-3444 1775);
FORCEPROP 2 LAST $XR0 198 
J 0
(-3564 1775);
DISPLAY 0.638298 (-3564 1775);
PAINT MONO (-3564 1775);
FORCEPROP 2 LAST CDS_LIB standard
J 0
(-3750 1775);
DISPLAY INVISIBLE (-3750 1775);
FORCEPROP 1 LAST OFFPAGE TRUE
J 0
(-3425 1650);
DISPLAY 0.872340 (-3425 1650);
PAINT GREEN (-3425 1650);
DISPLAY INVISIBLE (-3425 1650);
FORCEPROP 1 LAST COMMENT_BODY TRUE
J 0
(-3775 1675);
DISPLAY 0.872340 (-3775 1675);
PAINT GREEN (-3775 1675);
DISPLAY INVISIBLE (-3775 1675);
FORCEPROP 2 LAST PATH I404
J 0
(-3575 1850);
DISPLAY 1.021277 (-3575 1850);
DISPLAY INVISIBLE (-3575 1850);
FORCEADD Q_RES..2
(-9400 6250);
FORCEPROP 1 LAST LOCATION PR225
J 0
(-9355 6375);
DISPLAY 0.489362 (-9355 6375);
PAINT SKYBLUE (-9355 6375);
FORCEPROP 0 LAST $SEC 1
J 0
(-9350 6400);
DISPLAY 0.680851 (-9350 6400);
PAINT MONO (-9350 6400);
DISPLAY INVISIBLE (-9350 6400);
FORCEPROP 0 LAST CDS_SEC 1
J 0
(-9350 6400);
DISPLAY 1.021277 (-9350 6400);
DISPLAY INVISIBLE (-9350 6400);
FORCEPROP 1 LASTPIN (-9400 6350) $PN 1
J 0
(-9395 6312);
DISPLAY 0.489362 (-9395 6312);
PAINT MONO (-9395 6312);
FORCEPROP 1 LASTPIN (-9400 6150) $PN 2
J 0
(-9395 6160);
DISPLAY 0.489362 (-9395 6160);
PAINT MONO (-9395 6160);
FORCEPROP 1 LAST WATTAGE 1/16W
J 0
(-9375 6175);
DISPLAY 0.489362 (-9375 6175);
PAINT SKYBLUE (-9375 6175);
FORCEPROP 1 LAST MATERIAL EMPTY
J 0
(-9375 6125);
DISPLAY 0.489362 (-9375 6125);
PAINT RED (-9375 6125);
FORCEPROP 1 LAST TOLERANCE 1%
J 0
(-9370 6225);
DISPLAY 0.489362 (-9370 6225);
PAINT SKYBLUE (-9370 6225);
FORCEPROP 1 LAST VALUE 1K
J 0
(-9370 6275);
DISPLAY 0.489362 (-9370 6275);
PAINT SKYBLUE (-9370 6275);
FORCEPROP 1 LAST PART_NUMBER TMP_QCS21002FB24
J 0
(-9375 6075);
DISPLAY 0.489362 (-9375 6075);
PAINT SKYBLUE (-9375 6075);
FORCEPROP 1 LAST PACK_TYPE 0402LF
J 0
(-9375 6025);
DISPLAY 0.489362 (-9375 6025);
PAINT SKYBLUE (-9375 6025);
FORCEPROP 2 LAST CDS_LIB pure_quanta
J 0
(-9400 6250);
DISPLAY INVISIBLE (-9400 6250);
FORCEPROP 1 LAST PATH I408
J 0
(-9350 6425);
DISPLAY 0.978723 (-9350 6425);
PAINT WHITE (-9350 6425);
DISPLAY INVISIBLE (-9350 6425);
FORCEADD Q_RES..2
(-10150 6250);
FORCEPROP 1 LAST LOCATION PR218
J 0
(-10105 6375);
DISPLAY 0.489362 (-10105 6375);
PAINT SKYBLUE (-10105 6375);
FORCEPROP 0 LAST $SEC 1
J 0
(-10100 6400);
DISPLAY 0.680851 (-10100 6400);
PAINT MONO (-10100 6400);
DISPLAY INVISIBLE (-10100 6400);
FORCEPROP 0 LAST CDS_SEC 1
J 0
(-10100 6400);
DISPLAY 1.021277 (-10100 6400);
DISPLAY INVISIBLE (-10100 6400);
FORCEPROP 1 LASTPIN (-10150 6350) $PN 1
J 0
(-10145 6312);
DISPLAY 0.489362 (-10145 6312);
PAINT MONO (-10145 6312);
FORCEPROP 1 LASTPIN (-10150 6150) $PN 2
J 0
(-10145 6160);
DISPLAY 0.489362 (-10145 6160);
PAINT MONO (-10145 6160);
FORCEPROP 1 LAST WATTAGE 1/16W
J 0
(-10125 6175);
DISPLAY 0.489362 (-10125 6175);
PAINT SKYBLUE (-10125 6175);
FORCEPROP 1 LAST MATERIAL EMPTY
J 0
(-10125 6125);
DISPLAY 0.489362 (-10125 6125);
PAINT RED (-10125 6125);
FORCEPROP 1 LAST TOLERANCE 1%
J 0
(-10120 6225);
DISPLAY 0.489362 (-10120 6225);
PAINT SKYBLUE (-10120 6225);
FORCEPROP 1 LAST VALUE 1K
J 0
(-10120 6275);
DISPLAY 0.489362 (-10120 6275);
PAINT SKYBLUE (-10120 6275);
FORCEPROP 1 LAST PACK_TYPE 0402LF
J 0
(-10125 6075);
DISPLAY 0.489362 (-10125 6075);
PAINT SKYBLUE (-10125 6075);
FORCEPROP 2 LAST CDS_LIB pure_quanta
J 0
(-10150 6250);
DISPLAY INVISIBLE (-10150 6250);
FORCEPROP 1 LAST PATH I409
J 0
(-10100 6425);
DISPLAY 0.978723 (-10100 6425);
PAINT WHITE (-10100 6425);
DISPLAY INVISIBLE (-10100 6425);
FORCEPROP 1 LAST PART_NUMBER TMP_QCS21002FB24
J 0
(-10125 6075);
DISPLAY 0.489362 (-10125 6075);
PAINT SKYBLUE (-10125 6075);
DISPLAY INVISIBLE (-10125 6075);
FORCEADD Q_RES..2
(-9775 6250);
FORCEPROP 1 LAST LOCATION PR220
J 0
(-9730 6375);
DISPLAY 0.489362 (-9730 6375);
PAINT SKYBLUE (-9730 6375);
FORCEPROP 0 LAST $SEC 1
J 0
(-9725 6400);
DISPLAY 0.680851 (-9725 6400);
PAINT MONO (-9725 6400);
DISPLAY INVISIBLE (-9725 6400);
FORCEPROP 0 LAST CDS_SEC 1
J 0
(-9725 6400);
DISPLAY 1.021277 (-9725 6400);
DISPLAY INVISIBLE (-9725 6400);
FORCEPROP 1 LASTPIN (-9775 6350) $PN 1
J 0
(-9770 6312);
DISPLAY 0.489362 (-9770 6312);
PAINT MONO (-9770 6312);
FORCEPROP 1 LASTPIN (-9775 6150) $PN 2
J 0
(-9770 6160);
DISPLAY 0.489362 (-9770 6160);
PAINT MONO (-9770 6160);
FORCEPROP 1 LAST WATTAGE 1/16W
J 0
(-9750 6175);
DISPLAY 0.489362 (-9750 6175);
PAINT SKYBLUE (-9750 6175);
FORCEPROP 1 LAST MATERIAL EMPTY
J 0
(-9750 6125);
DISPLAY 0.489362 (-9750 6125);
PAINT RED (-9750 6125);
FORCEPROP 1 LAST TOLERANCE 1%
J 0
(-9745 6225);
DISPLAY 0.489362 (-9745 6225);
PAINT SKYBLUE (-9745 6225);
FORCEPROP 1 LAST VALUE 1K
J 0
(-9745 6275);
DISPLAY 0.489362 (-9745 6275);
PAINT SKYBLUE (-9745 6275);
FORCEPROP 1 LAST PACK_TYPE 0402LF
J 0
(-9750 6075);
DISPLAY 0.489362 (-9750 6075);
PAINT SKYBLUE (-9750 6075);
FORCEPROP 2 LAST CDS_LIB pure_quanta
J 0
(-9775 6250);
DISPLAY INVISIBLE (-9775 6250);
FORCEPROP 1 LAST PATH I410
J 0
(-9725 6425);
DISPLAY 0.978723 (-9725 6425);
PAINT WHITE (-9725 6425);
DISPLAY INVISIBLE (-9725 6425);
FORCEPROP 1 LAST PART_NUMBER TMP_QCS21002FB24
J 0
(-9750 6075);
DISPLAY 0.489362 (-9750 6075);
PAINT SKYBLUE (-9750 6075);
DISPLAY INVISIBLE (-9750 6075);
FORCEADD Q_RES..2
(-9600 6250);
FORCEPROP 1 LAST LOCATION PR222
J 0
(-9555 6375);
DISPLAY 0.489362 (-9555 6375);
PAINT SKYBLUE (-9555 6375);
FORCEPROP 0 LAST $SEC 1
J 0
(-9550 6400);
DISPLAY 0.680851 (-9550 6400);
PAINT MONO (-9550 6400);
DISPLAY INVISIBLE (-9550 6400);
FORCEPROP 0 LAST CDS_SEC 1
J 0
(-9550 6400);
DISPLAY 1.021277 (-9550 6400);
DISPLAY INVISIBLE (-9550 6400);
FORCEPROP 1 LASTPIN (-9600 6350) $PN 1
J 0
(-9595 6312);
DISPLAY 0.489362 (-9595 6312);
PAINT MONO (-9595 6312);
FORCEPROP 1 LASTPIN (-9600 6150) $PN 2
J 0
(-9595 6160);
DISPLAY 0.489362 (-9595 6160);
PAINT MONO (-9595 6160);
FORCEPROP 1 LAST WATTAGE 1/16W
J 0
(-9575 6175);
DISPLAY 0.489362 (-9575 6175);
PAINT SKYBLUE (-9575 6175);
FORCEPROP 1 LAST MATERIAL EMPTY
J 0
(-9575 6125);
DISPLAY 0.489362 (-9575 6125);
PAINT RED (-9575 6125);
FORCEPROP 1 LAST TOLERANCE 1%
J 0
(-9570 6225);
DISPLAY 0.489362 (-9570 6225);
PAINT SKYBLUE (-9570 6225);
FORCEPROP 1 LAST VALUE 1K
J 0
(-9570 6275);
DISPLAY 0.489362 (-9570 6275);
PAINT SKYBLUE (-9570 6275);
FORCEPROP 1 LAST PACK_TYPE 0402LF
J 0
(-9575 6075);
DISPLAY 0.489362 (-9575 6075);
PAINT SKYBLUE (-9575 6075);
FORCEPROP 2 LAST CDS_LIB pure_quanta
J 0
(-9600 6250);
DISPLAY INVISIBLE (-9600 6250);
FORCEPROP 1 LAST PATH I411
J 0
(-9550 6425);
DISPLAY 0.978723 (-9550 6425);
PAINT WHITE (-9550 6425);
DISPLAY INVISIBLE (-9550 6425);
FORCEPROP 1 LAST PART_NUMBER TMP_QCS21002FB24
J 0
(-9575 6075);
DISPLAY 0.489362 (-9575 6075);
PAINT SKYBLUE (-9575 6075);
DISPLAY INVISIBLE (-9575 6075);
FORCEADD Q_RES..2
(-10025 5275);
FORCEPROP 1 LAST LOCATION PR219
J 0
(-9980 5400);
DISPLAY 0.489362 (-9980 5400);
PAINT SKYBLUE (-9980 5400);
FORCEPROP 0 LAST $SEC 1
J 0
(-9975 5425);
DISPLAY 0.680851 (-9975 5425);
PAINT MONO (-9975 5425);
DISPLAY INVISIBLE (-9975 5425);
FORCEPROP 0 LAST CDS_SEC 1
J 0
(-9975 5425);
DISPLAY 1.021277 (-9975 5425);
DISPLAY INVISIBLE (-9975 5425);
FORCEPROP 1 LASTPIN (-10025 5375) $PN 1
J 0
(-10020 5337);
DISPLAY 0.489362 (-10020 5337);
PAINT MONO (-10020 5337);
FORCEPROP 1 LASTPIN (-10025 5175) $PN 2
J 0
(-10020 5185);
DISPLAY 0.489362 (-10020 5185);
PAINT MONO (-10020 5185);
FORCEPROP 1 LAST MATERIAL EMPTY
J 0
(-10000 5150);
DISPLAY 0.489362 (-10000 5150);
PAINT RED (-10000 5150);
FORCEPROP 1 LAST TOLERANCE 1%
J 0
(-9995 5250);
DISPLAY 0.489362 (-9995 5250);
PAINT SKYBLUE (-9995 5250);
FORCEPROP 1 LAST VALUE 1K
J 0
(-9995 5300);
DISPLAY 0.489362 (-9995 5300);
PAINT SKYBLUE (-9995 5300);
FORCEPROP 1 LAST PACK_TYPE 0402LF
J 0
(-10000 5100);
DISPLAY 0.489362 (-10000 5100);
PAINT SKYBLUE (-10000 5100);
FORCEPROP 1 LAST WATTAGE 1/16W
J 0
(-10000 5200);
DISPLAY 0.489362 (-10000 5200);
PAINT SKYBLUE (-10000 5200);
FORCEPROP 2 LAST CDS_LIB pure_quanta
J 0
(-10025 5275);
DISPLAY INVISIBLE (-10025 5275);
FORCEPROP 1 LAST PATH I414
J 0
(-9975 5450);
DISPLAY 0.978723 (-9975 5450);
PAINT WHITE (-9975 5450);
DISPLAY INVISIBLE (-9975 5450);
FORCEPROP 1 LAST PART_NUMBER TMP_QCS21002FB24
J 0
(-10000 5100);
DISPLAY 0.489362 (-10000 5100);
PAINT SKYBLUE (-10000 5100);
DISPLAY INVISIBLE (-10000 5100);
FORCEADD Q_RES..2
(-10200 5275);
FORCEPROP 1 LAST LOCATION PR217
J 0
(-10155 5400);
DISPLAY 0.489362 (-10155 5400);
PAINT SKYBLUE (-10155 5400);
FORCEPROP 0 LAST $SEC 1
J 0
(-10150 5425);
DISPLAY 0.680851 (-10150 5425);
PAINT MONO (-10150 5425);
DISPLAY INVISIBLE (-10150 5425);
FORCEPROP 0 LAST CDS_SEC 1
J 0
(-10150 5425);
DISPLAY 1.021277 (-10150 5425);
DISPLAY INVISIBLE (-10150 5425);
FORCEPROP 1 LASTPIN (-10200 5375) $PN 1
J 0
(-10195 5337);
DISPLAY 0.489362 (-10195 5337);
PAINT MONO (-10195 5337);
FORCEPROP 1 LASTPIN (-10200 5175) $PN 2
J 0
(-10195 5185);
DISPLAY 0.489362 (-10195 5185);
PAINT MONO (-10195 5185);
FORCEPROP 1 LAST WATTAGE 1/16W
J 0
(-10175 5200);
DISPLAY 0.489362 (-10175 5200);
PAINT SKYBLUE (-10175 5200);
FORCEPROP 1 LAST MATERIAL CHIP
J 0
(-10175 5150);
DISPLAY 0.489362 (-10175 5150);
PAINT SKYBLUE (-10175 5150);
FORCEPROP 1 LAST TOLERANCE 5%
J 0
(-10170 5250);
DISPLAY 0.489362 (-10170 5250);
PAINT SKYBLUE (-10170 5250);
FORCEPROP 1 LAST VALUE 0
J 0
(-10170 5300);
DISPLAY 0.489362 (-10170 5300);
PAINT SKYBLUE (-10170 5300);
FORCEPROP 1 LAST PACK_TYPE 0402LF
J 0
(-10175 5100);
DISPLAY 0.489362 (-10175 5100);
PAINT SKYBLUE (-10175 5100);
FORCEPROP 2 LAST CDS_LIB pure_quanta
J 0
(-10200 5275);
DISPLAY INVISIBLE (-10200 5275);
FORCEPROP 1 LAST PATH I415
J 0
(-10150 5450);
DISPLAY 0.978723 (-10150 5450);
PAINT WHITE (-10150 5450);
DISPLAY INVISIBLE (-10150 5450);
FORCEPROP 1 LAST PART_NUMBER CS00002JB38
J 0
(-10175 5100);
DISPLAY 0.489362 (-10175 5100);
PAINT SKYBLUE (-10175 5100);
DISPLAY INVISIBLE (-10175 5100);
FORCEADD UNIVERSAL_GND..1
(-10200 4825);
FORCEPROP 3 LASTPIN (-10200 4875) SIG_NAME GND\g
J 0
(-10190 4885);
DISPLAY 0.659574 (-10190 4885);
PAINT MONO (-10190 4885);
DISPLAY INVISIBLE (-10190 4885);
FORCEPROP 2 LAST CDS_LIB pure_quanta_power
J 0
(-10200 4825);
DISPLAY INVISIBLE (-10200 4825);
FORCEPROP 1 LAST PATH I416
J 0
(-10125 4825);
DISPLAY 0.872340 (-10125 4825);
PAINT AQUA (-10125 4825);
DISPLAY INVISIBLE (-10125 4825);
FORCEPROP 1 LAST HDL_POWER GND
J 1
(-10175 4750);
DISPLAY 0.872340 (-10175 4750);
PAINT GREEN (-10175 4750);
DISPLAY INVISIBLE (-10175 4750);
FORCEADD VCC_CORE..1
(-10150 6600);
FORCEPROP 3 LASTPIN (-10150 6550) SIG_NAME PVDD18_S5_P1\g
J 0
(-10140 6560);
DISPLAY 0.659574 (-10140 6560);
PAINT MONO (-10140 6560);
DISPLAY INVISIBLE (-10140 6560);
FORCEPROP 1 LAST HDL_POWER PVDD18_S5_P1
J 1
(-10150 6650);
DISPLAY 0.489362 (-10150 6650);
PAINT GREEN (-10150 6650);
FORCEPROP 2 LAST CDS_LIB pure_quanta_power
J 0
(-10150 6600);
DISPLAY INVISIBLE (-10150 6600);
FORCEPROP 1 LAST PATH I417
J 0
(-10100 6625);
DISPLAY 0.872340 (-10100 6625);
PAINT AQUA (-10100 6625);
DISPLAY INVISIBLE (-10100 6625);
FORCEADD UNIVERSAL_GND..1
(-4350 6000);
FORCEPROP 3 LASTPIN (-4350 6050) SIG_NAME GND\g
J 0
(-4340 6060);
DISPLAY 0.659574 (-4340 6060);
PAINT MONO (-4340 6060);
DISPLAY INVISIBLE (-4340 6060);
FORCEPROP 2 LAST CDS_LIB pure_quanta_power
J 0
(-4350 6000);
DISPLAY INVISIBLE (-4350 6000);
FORCEPROP 1 LAST PATH I418
J 0
(-4275 6000);
DISPLAY 0.872340 (-4275 6000);
PAINT AQUA (-4275 6000);
DISPLAY INVISIBLE (-4275 6000);
FORCEPROP 1 LAST HDL_POWER GND
J 1
(-4325 5925);
DISPLAY 0.872340 (-4325 5925);
PAINT GREEN (-4325 5925);
DISPLAY INVISIBLE (-4325 5925);
FORCEADD UNIVERSAL_GND..1
(-4350 5525);
FORCEPROP 3 LASTPIN (-4350 5575) SIG_NAME GND\g
J 0
(-4340 5585);
DISPLAY 0.659574 (-4340 5585);
PAINT MONO (-4340 5585);
DISPLAY INVISIBLE (-4340 5585);
FORCEPROP 2 LAST CDS_LIB pure_quanta_power
J 0
(-4350 5525);
DISPLAY INVISIBLE (-4350 5525);
FORCEPROP 1 LAST PATH I419
J 0
(-4275 5525);
DISPLAY 0.872340 (-4275 5525);
PAINT AQUA (-4275 5525);
DISPLAY INVISIBLE (-4275 5525);
FORCEPROP 1 LAST HDL_POWER GND
J 1
(-4325 5450);
DISPLAY 0.872340 (-4325 5450);
PAINT GREEN (-4325 5450);
DISPLAY INVISIBLE (-4325 5450);
FORCEADD VCC_CORE..1
(-7875 2800);
FORCEPROP 3 LASTPIN (-7875 2750) SIG_NAME PVDD18_S5_P1\g
J 0
(-7865 2760);
DISPLAY 0.659574 (-7865 2760);
PAINT MONO (-7865 2760);
DISPLAY INVISIBLE (-7865 2760);
FORCEPROP 1 LAST HDL_POWER PVDD18_S5_P1
J 1
(-7875 2850);
DISPLAY 0.489362 (-7875 2850);
PAINT GREEN (-7875 2850);
FORCEPROP 2 LAST CDS_LIB pure_quanta_power
J 0
(-7875 2800);
DISPLAY INVISIBLE (-7875 2800);
FORCEPROP 1 LAST PATH I423
J 0
(-7825 2825);
DISPLAY 0.872340 (-7825 2825);
PAINT AQUA (-7825 2825);
DISPLAY INVISIBLE (-7825 2825);
FORCEADD MOSFET_PCH_GDS_ESD_PROTECTED..1
R 6
(-8525 2200);
FORCEPROP 1 LAST LOCATION PQ12
J 0
(-8350 2050);
DISPLAY 0.489362 (-8350 2050);
PAINT SKYBLUE (-8350 2050);
FORCEPROP 0 LAST $SEC 1
J 0
(-8350 2225);
DISPLAY 0.680851 (-8350 2225);
PAINT MONO (-8350 2225);
DISPLAY INVISIBLE (-8350 2225);
FORCEPROP 0 LAST CDS_SEC 1
J 0
(-8350 2225);
DISPLAY 1.021277 (-8350 2225);
DISPLAY INVISIBLE (-8350 2225);
FORCEPROP 0 LASTPIN (-8500 1900) $PN D
R 1
J 2
(-8510 1890);
DISPLAY 0.489362 (-8510 1890);
PAINT MONO (-8510 1890);
FORCEPROP 0 LASTPIN (-8800 2200) $PN G
J 2
(-8810 2210);
DISPLAY 0.489362 (-8810 2210);
PAINT MONO (-8810 2210);
FORCEPROP 0 LASTPIN (-8500 2500) $PN S
R 1
J 0
(-8510 2510);
DISPLAY 0.489362 (-8510 2510);
PAINT MONO (-8510 2510);
FORCEPROP 1 LAST MATERIAL IC
J 0
(-8350 2202);
DISPLAY 0.489362 (-8350 2202);
PAINT SKYBLUE (-8350 2202);
FORCEPROP 2 LAST VALUE PJA3415AE
J 0
(-8350 2152);
DISPLAY 0.489362 (-8350 2152);
PAINT SKYBLUE (-8350 2152);
FORCEPROP 1 LAST PART_NUMBER BAM34150008
J 0
(-8350 2102);
DISPLAY 0.489362 (-8350 2102);
PAINT SKYBLUE (-8350 2102);
FORCEPROP 1 LAST CDS_LMAN_SYM_OUTLINE -125,150,125,-150
J 0
(-8525 2200);
DISPLAY 0.468085 (-8525 2200);
PAINT GREEN (-8525 2200);
DISPLAY INVISIBLE (-8525 2200);
FORCEPROP 2 LAST CDS_LIB pure_quanta
J 0
(-8525 2200);
DISPLAY INVISIBLE (-8525 2200);
FORCEPROP 1 LAST NEEDS_NO_SIZE TRUE
J 0
(-8525 2166);
DISPLAY 0.723404 (-8525 2166);
PAINT GREEN (-8525 2166);
DISPLAY INVISIBLE (-8525 2166);
FORCEPROP 2 LAST PART_TYPE SMLF
J 0
(-8375 2027);
DISPLAY 1.021277 (-8375 2027);
DISPLAY INVISIBLE (-8375 2027);
FORCEPROP 1 LAST PATH I424
J 0
(-8525 2200);
DISPLAY 0.723404 (-8525 2200);
PAINT GREEN (-8525 2200);
DISPLAY INVISIBLE (-8525 2200);
FORCEADD UNIVERSAL_GND..1
(-4725 5525);
FORCEPROP 3 LASTPIN (-4725 5575) SIG_NAME GND\g
J 0
(-4715 5585);
DISPLAY 0.659574 (-4715 5585);
PAINT MONO (-4715 5585);
DISPLAY INVISIBLE (-4715 5585);
FORCEPROP 2 LAST CDS_LIB pure_quanta_power
J 0
(-4725 5525);
DISPLAY INVISIBLE (-4725 5525);
FORCEPROP 1 LAST PATH I425
J 0
(-4650 5525);
DISPLAY 0.872340 (-4650 5525);
PAINT AQUA (-4650 5525);
DISPLAY INVISIBLE (-4650 5525);
FORCEPROP 1 LAST HDL_POWER GND
J 1
(-4700 5450);
DISPLAY 0.872340 (-4700 5450);
PAINT GREEN (-4700 5450);
DISPLAY INVISIBLE (-4700 5450);
FORCEADD Q_CAP..1
(-4725 5750);
FORCEPROP 1 LAST LOCATION PC93
J 0
(-4675 5850);
DISPLAY 0.489362 (-4675 5850);
PAINT SKYBLUE (-4675 5850);
FORCEPROP 0 LAST $SEC 1
J 0
(-4675 5875);
DISPLAY 0.680851 (-4675 5875);
PAINT MONO (-4675 5875);
DISPLAY INVISIBLE (-4675 5875);
FORCEPROP 0 LAST CDS_SEC 1
J 0
(-4675 5875);
DISPLAY 1.021277 (-4675 5875);
DISPLAY INVISIBLE (-4675 5875);
FORCEPROP 1 LASTPIN (-4725 5850) $PN 1
J 0
(-4715 5830);
DISPLAY 0.489362 (-4715 5830);
PAINT MONO (-4715 5830);
FORCEPROP 1 LASTPIN (-4725 5650) $PN 2
J 0
(-4715 5630);
DISPLAY 0.489362 (-4715 5630);
PAINT MONO (-4715 5630);
FORCEPROP 1 LAST MATERIAL X7R
J 0
(-4675 5650);
DISPLAY 0.489362 (-4675 5650);
PAINT SKYBLUE (-4675 5650);
FORCEPROP 1 LAST TOLERANCE 10%
J 0
(-4675 5700);
DISPLAY 0.489362 (-4675 5700);
PAINT SKYBLUE (-4675 5700);
FORCEPROP 1 LAST VALUE 0.1UF
J 0
(-4675 5800);
DISPLAY 0.489362 (-4675 5800);
PAINT SKYBLUE (-4675 5800);
FORCEPROP 1 LAST PART_NUMBER CH4104K1B00
J 0
(-4675 5600);
DISPLAY 0.489362 (-4675 5600);
PAINT SKYBLUE (-4675 5600);
FORCEPROP 1 LAST VOLTAGE 25V
J 0
(-4675 5750);
DISPLAY 0.489362 (-4675 5750);
PAINT SKYBLUE (-4675 5750);
FORCEPROP 1 LAST PACK_TYPE 0402
J 0
(-4675 5550);
DISPLAY 0.489362 (-4675 5550);
PAINT SKYBLUE (-4675 5550);
FORCEPROP 2 LAST CDS_LIB pure_quanta
J 0
(-4725 5750);
DISPLAY INVISIBLE (-4725 5750);
FORCEPROP 1 LAST PATH I426
J 0
(-4675 5900);
DISPLAY 0.978723 (-4675 5900);
PAINT WHITE (-4675 5900);
DISPLAY INVISIBLE (-4675 5900);
FORCEADD UNIVERSAL_GND..1
(-4725 6000);
FORCEPROP 3 LASTPIN (-4725 6050) SIG_NAME GND\g
J 0
(-4715 6060);
DISPLAY 0.659574 (-4715 6060);
PAINT MONO (-4715 6060);
DISPLAY INVISIBLE (-4715 6060);
FORCEPROP 2 LAST CDS_LIB pure_quanta_power
J 0
(-4725 6000);
DISPLAY INVISIBLE (-4725 6000);
FORCEPROP 1 LAST PATH I427
J 0
(-4650 6000);
DISPLAY 0.872340 (-4650 6000);
PAINT AQUA (-4650 6000);
DISPLAY INVISIBLE (-4650 6000);
FORCEPROP 1 LAST HDL_POWER GND
J 1
(-4700 5925);
DISPLAY 0.872340 (-4700 5925);
PAINT GREEN (-4700 5925);
DISPLAY INVISIBLE (-4700 5925);
FORCEADD Q_CAP..1
(-4725 6225);
FORCEPROP 1 LAST LOCATION PC29
J 0
(-4675 6325);
DISPLAY 0.489362 (-4675 6325);
PAINT SKYBLUE (-4675 6325);
FORCEPROP 0 LAST $SEC 1
J 0
(-4675 6350);
DISPLAY 0.680851 (-4675 6350);
PAINT MONO (-4675 6350);
DISPLAY INVISIBLE (-4675 6350);
FORCEPROP 0 LAST CDS_SEC 1
J 0
(-4675 6350);
DISPLAY 1.021277 (-4675 6350);
DISPLAY INVISIBLE (-4675 6350);
FORCEPROP 1 LASTPIN (-4725 6325) $PN 1
J 0
(-4715 6305);
DISPLAY 0.489362 (-4715 6305);
PAINT MONO (-4715 6305);
FORCEPROP 1 LASTPIN (-4725 6125) $PN 2
J 0
(-4715 6105);
DISPLAY 0.489362 (-4715 6105);
PAINT MONO (-4715 6105);
FORCEPROP 1 LAST MATERIAL X7R
J 0
(-4675 6125);
DISPLAY 0.489362 (-4675 6125);
PAINT SKYBLUE (-4675 6125);
FORCEPROP 1 LAST TOLERANCE 10%
J 0
(-4675 6175);
DISPLAY 0.489362 (-4675 6175);
PAINT SKYBLUE (-4675 6175);
FORCEPROP 1 LAST VALUE 0.1UF
J 0
(-4675 6275);
DISPLAY 0.489362 (-4675 6275);
PAINT SKYBLUE (-4675 6275);
FORCEPROP 1 LAST PART_NUMBER CH4104K1B00
J 0
(-4675 6075);
DISPLAY 0.489362 (-4675 6075);
PAINT SKYBLUE (-4675 6075);
FORCEPROP 1 LAST VOLTAGE 25V
J 0
(-4675 6225);
DISPLAY 0.489362 (-4675 6225);
PAINT SKYBLUE (-4675 6225);
FORCEPROP 1 LAST PACK_TYPE 0402
J 0
(-4675 6025);
DISPLAY 0.489362 (-4675 6025);
PAINT SKYBLUE (-4675 6025);
FORCEPROP 2 LAST CDS_LIB pure_quanta
J 0
(-4725 6225);
DISPLAY INVISIBLE (-4725 6225);
FORCEPROP 1 LAST PATH I428
J 0
(-4675 6375);
DISPLAY 0.978723 (-4675 6375);
PAINT WHITE (-4675 6375);
DISPLAY INVISIBLE (-4675 6375);
FORCEADD OFFPAGE..1
(-10225 5925);
FORCEPROP 2 LAST $XR0 54 
J 0
(-10446 5925);
DISPLAY 0.638298 (-10446 5925);
PAINT MONO (-10446 5925);
FORCEPROP 2 LAST CDS_LIB standard
J 0
(-10225 5925);
DISPLAY INVISIBLE (-10225 5925);
FORCEPROP 1 LAST OFFPAGE TRUE
J 0
(-9900 5800);
DISPLAY 0.872340 (-9900 5800);
PAINT GREEN (-9900 5800);
DISPLAY INVISIBLE (-9900 5800);
FORCEPROP 1 LAST COMMENT_BODY TRUE
J 0
(-10100 5825);
DISPLAY 0.872340 (-10100 5825);
PAINT GREEN (-10100 5825);
DISPLAY INVISIBLE (-10100 5825);
FORCEPROP 2 LAST PATH I437
J 0
(-10175 6000);
DISPLAY 1.021277 (-10175 6000);
DISPLAY INVISIBLE (-10175 6000);
FORCEADD OFFPAGE..1
(-10225 5775);
FORCEPROP 2 LAST $XR0 54 
J 0
(-10446 5775);
DISPLAY 0.638298 (-10446 5775);
PAINT MONO (-10446 5775);
FORCEPROP 2 LAST CDS_LIB standard
J 0
(-10225 5775);
DISPLAY INVISIBLE (-10225 5775);
FORCEPROP 1 LAST OFFPAGE TRUE
J 0
(-9900 5650);
DISPLAY 0.872340 (-9900 5650);
PAINT GREEN (-9900 5650);
DISPLAY INVISIBLE (-9900 5650);
FORCEPROP 1 LAST COMMENT_BODY TRUE
J 0
(-10100 5675);
DISPLAY 0.872340 (-10100 5675);
PAINT GREEN (-10100 5675);
DISPLAY INVISIBLE (-10100 5675);
FORCEPROP 2 LAST PATH I438
J 0
(-10175 5850);
DISPLAY 1.021277 (-10175 5850);
DISPLAY INVISIBLE (-10175 5850);
FORCEADD Q_CAP..1
(-9450 5275);
FORCEPROP 1 LAST LOCATION PC310
J 0
(-9400 5375);
DISPLAY 0.489362 (-9400 5375);
PAINT SKYBLUE (-9400 5375);
FORCEPROP 0 LAST $SEC 1
J 0
(-9400 5400);
DISPLAY 0.680851 (-9400 5400);
PAINT MONO (-9400 5400);
DISPLAY INVISIBLE (-9400 5400);
FORCEPROP 0 LAST CDS_SEC 1
J 0
(-9400 5400);
DISPLAY 1.021277 (-9400 5400);
DISPLAY INVISIBLE (-9400 5400);
FORCEPROP 1 LASTPIN (-9450 5375) $PN 1
J 0
(-9440 5355);
DISPLAY 0.489362 (-9440 5355);
PAINT MONO (-9440 5355);
FORCEPROP 1 LASTPIN (-9450 5175) $PN 2
J 0
(-9440 5155);
DISPLAY 0.489362 (-9440 5155);
PAINT MONO (-9440 5155);
FORCEPROP 1 LAST MATERIAL EMPTY
J 0
(-9400 5175);
DISPLAY 0.489362 (-9400 5175);
PAINT RED (-9400 5175);
FORCEPROP 1 LAST TOLERANCE 5%
J 0
(-9400 5225);
DISPLAY 0.489362 (-9400 5225);
PAINT SKYBLUE (-9400 5225);
FORCEPROP 1 LAST VALUE 10PF
J 0
(-9400 5325);
DISPLAY 0.489362 (-9400 5325);
PAINT SKYBLUE (-9400 5325);
FORCEPROP 1 LAST PART_NUMBER CH01006JB08
J 0
(-9400 5125);
DISPLAY 0.489362 (-9400 5125);
PAINT SKYBLUE (-9400 5125);
FORCEPROP 1 LAST VOLTAGE 50V
J 0
(-9400 5275);
DISPLAY 0.489362 (-9400 5275);
PAINT SKYBLUE (-9400 5275);
FORCEPROP 1 LAST PACK_TYPE 0402
J 0
(-9400 5075);
DISPLAY 0.489362 (-9400 5075);
PAINT SKYBLUE (-9400 5075);
FORCEPROP 2 LAST CDS_LIB pure_quanta
J 0
(-9450 5275);
DISPLAY INVISIBLE (-9450 5275);
FORCEPROP 1 LAST PATH I499
J 0
(-9400 5425);
DISPLAY 0.978723 (-9400 5425);
PAINT WHITE (-9400 5425);
DISPLAY INVISIBLE (-9400 5425);
FORCEADD Q_CAP..1
(-9650 5275);
FORCEPROP 1 LAST LOCATION PC309
J 0
(-9600 5375);
DISPLAY 0.489362 (-9600 5375);
PAINT SKYBLUE (-9600 5375);
FORCEPROP 0 LAST $SEC 1
J 0
(-9600 5400);
DISPLAY 0.680851 (-9600 5400);
PAINT MONO (-9600 5400);
DISPLAY INVISIBLE (-9600 5400);
FORCEPROP 0 LAST CDS_SEC 1
J 0
(-9600 5400);
DISPLAY 1.021277 (-9600 5400);
DISPLAY INVISIBLE (-9600 5400);
FORCEPROP 1 LASTPIN (-9650 5375) $PN 1
J 0
(-9640 5355);
DISPLAY 0.489362 (-9640 5355);
PAINT MONO (-9640 5355);
FORCEPROP 1 LASTPIN (-9650 5175) $PN 2
J 0
(-9640 5155);
DISPLAY 0.489362 (-9640 5155);
PAINT MONO (-9640 5155);
FORCEPROP 1 LAST MATERIAL EMPTY
J 0
(-9600 5175);
DISPLAY 0.489362 (-9600 5175);
PAINT RED (-9600 5175);
FORCEPROP 1 LAST TOLERANCE 5%
J 0
(-9600 5225);
DISPLAY 0.489362 (-9600 5225);
PAINT SKYBLUE (-9600 5225);
FORCEPROP 1 LAST VALUE 10PF
J 0
(-9600 5325);
DISPLAY 0.489362 (-9600 5325);
PAINT SKYBLUE (-9600 5325);
FORCEPROP 1 LAST VOLTAGE 50V
J 0
(-9600 5275);
DISPLAY 0.489362 (-9600 5275);
PAINT SKYBLUE (-9600 5275);
FORCEPROP 1 LAST PACK_TYPE 0402
J 0
(-9600 5075);
DISPLAY 0.489362 (-9600 5075);
PAINT SKYBLUE (-9600 5075);
FORCEPROP 2 LAST CDS_LIB pure_quanta
J 0
(-9650 5275);
DISPLAY INVISIBLE (-9650 5275);
FORCEPROP 1 LAST PATH I500
J 0
(-9600 5425);
DISPLAY 0.978723 (-9600 5425);
PAINT WHITE (-9600 5425);
DISPLAY INVISIBLE (-9600 5425);
FORCEPROP 1 LAST PART_NUMBER CH01006JB08
J 0
(-9600 5125);
DISPLAY 0.489362 (-9600 5125);
PAINT SKYBLUE (-9600 5125);
DISPLAY INVISIBLE (-9600 5125);
FORCEADD Q_CAP..1
(-9850 5250);
FORCEPROP 1 LAST LOCATION PC308
J 0
(-9800 5350);
DISPLAY 0.489362 (-9800 5350);
PAINT SKYBLUE (-9800 5350);
FORCEPROP 0 LAST $SEC 1
J 0
(-9800 5375);
DISPLAY 0.680851 (-9800 5375);
PAINT MONO (-9800 5375);
DISPLAY INVISIBLE (-9800 5375);
FORCEPROP 0 LAST CDS_SEC 1
J 0
(-9800 5375);
DISPLAY 1.021277 (-9800 5375);
DISPLAY INVISIBLE (-9800 5375);
FORCEPROP 1 LASTPIN (-9850 5350) $PN 1
J 0
(-9840 5330);
DISPLAY 0.489362 (-9840 5330);
PAINT MONO (-9840 5330);
FORCEPROP 1 LASTPIN (-9850 5150) $PN 2
J 0
(-9840 5130);
DISPLAY 0.489362 (-9840 5130);
PAINT MONO (-9840 5130);
FORCEPROP 1 LAST MATERIAL EMPTY
J 0
(-9800 5150);
DISPLAY 0.489362 (-9800 5150);
PAINT RED (-9800 5150);
FORCEPROP 1 LAST TOLERANCE 5%
J 0
(-9800 5200);
DISPLAY 0.489362 (-9800 5200);
PAINT SKYBLUE (-9800 5200);
FORCEPROP 1 LAST VALUE 10PF
J 0
(-9800 5300);
DISPLAY 0.489362 (-9800 5300);
PAINT SKYBLUE (-9800 5300);
FORCEPROP 1 LAST VOLTAGE 50V
J 0
(-9800 5250);
DISPLAY 0.489362 (-9800 5250);
PAINT SKYBLUE (-9800 5250);
FORCEPROP 1 LAST PACK_TYPE 0402
J 0
(-9800 5050);
DISPLAY 0.489362 (-9800 5050);
PAINT SKYBLUE (-9800 5050);
FORCEPROP 2 LAST CDS_LIB pure_quanta
J 0
(-9850 5250);
DISPLAY INVISIBLE (-9850 5250);
FORCEPROP 1 LAST PATH I501
J 0
(-9800 5400);
DISPLAY 0.978723 (-9800 5400);
PAINT WHITE (-9800 5400);
DISPLAY INVISIBLE (-9800 5400);
FORCEPROP 1 LAST PART_NUMBER CH01006JB08
J 0
(-9800 5100);
DISPLAY 0.489362 (-9800 5100);
PAINT SKYBLUE (-9800 5100);
DISPLAY INVISIBLE (-9800 5100);
FORCEADD Q_RES..1
(-8550 4525);
FORCEPROP 1 LAST LOCATION PR228
J 0
(-8600 4575);
DISPLAY 0.489362 (-8600 4575);
PAINT SKYBLUE (-8600 4575);
FORCEPROP 0 LAST $SEC 1
J 0
(-8175 4650);
DISPLAY 0.680851 (-8175 4650);
PAINT MONO (-8175 4650);
DISPLAY INVISIBLE (-8175 4650);
FORCEPROP 0 LAST CDS_SEC 1
J 0
(-8175 4650);
DISPLAY 1.021277 (-8175 4650);
DISPLAY INVISIBLE (-8175 4650);
FORCEPROP 1 LASTPIN (-8650 4525) $PN 1
J 0
(-8638 4537);
DISPLAY 0.489362 (-8638 4537);
PAINT MONO (-8638 4537);
FORCEPROP 1 LASTPIN (-8450 4525) $PN 2
J 0
(-8488 4537);
DISPLAY 0.489362 (-8488 4537);
PAINT MONO (-8488 4537);
FORCEPROP 1 LAST WATTAGE 1/16W
J 2
(-8325 4575);
DISPLAY 0.489362 (-8325 4575);
PAINT SKYBLUE (-8325 4575);
FORCEPROP 1 LAST MATERIAL CHIP
J 0
(-8450 4475);
DISPLAY 0.489362 (-8450 4475);
PAINT SKYBLUE (-8450 4475);
FORCEPROP 1 LAST PART_NUMBER CS04992FB31
J 0
(-8850 4450);
DISPLAY 0.489362 (-8850 4450);
PAINT SKYBLUE (-8850 4450);
FORCEPROP 1 LAST PACK_TYPE 0402LF
J 0
(-8475 4425);
DISPLAY 0.489362 (-8475 4425);
PAINT SKYBLUE (-8475 4425);
FORCEPROP 1 LAST VALUE 49.9
J 2
(-8525 4575);
DISPLAY 0.489362 (-8525 4575);
PAINT SKYBLUE (-8525 4575);
FORCEPROP 1 LAST TOLERANCE 1%
J 0
(-8700 4525);
DISPLAY 0.489362 (-8700 4525);
PAINT SKYBLUE (-8700 4525);
FORCEPROP 2 LAST CDS_LIB pure_quanta
J 0
(-8550 4525);
DISPLAY INVISIBLE (-8550 4525);
FORCEPROP 1 LAST PATH I502
J 0
(-8600 4675);
DISPLAY 0.978723 (-8600 4675);
PAINT WHITE (-8600 4675);
DISPLAY INVISIBLE (-8600 4675);
FORCEADD VCC_CORE..1
(-7875 4675);
FORCEPROP 3 LASTPIN (-7875 4625) SIG_NAME PVDDCR_CPU1_P1\g
J 0
(-7865 4635);
DISPLAY 0.659574 (-7865 4635);
PAINT MONO (-7865 4635);
DISPLAY INVISIBLE (-7865 4635);
FORCEPROP 1 LAST HDL_POWER PVDDCR_CPU1_P1
J 1
(-7875 4725);
DISPLAY 0.489362 (-7875 4725);
PAINT GREEN (-7875 4725);
FORCEPROP 2 LAST CDS_LIB pure_quanta_power
J 0
(-7875 4675);
DISPLAY INVISIBLE (-7875 4675);
FORCEPROP 1 LAST PATH I503
J 0
(-7825 4700);
DISPLAY 0.872340 (-7825 4700);
PAINT AQUA (-7825 4700);
DISPLAY INVISIBLE (-7825 4700);
FORCEADD Q_RES..1
(-8600 3850);
FORCEPROP 1 LAST LOCATION PR226
J 0
(-8650 3900);
DISPLAY 0.489362 (-8650 3900);
PAINT SKYBLUE (-8650 3900);
FORCEPROP 0 LAST $SEC 1
J 0
(-8225 3975);
DISPLAY 0.680851 (-8225 3975);
PAINT MONO (-8225 3975);
DISPLAY INVISIBLE (-8225 3975);
FORCEPROP 0 LAST CDS_SEC 1
J 0
(-8225 3975);
DISPLAY 1.021277 (-8225 3975);
DISPLAY INVISIBLE (-8225 3975);
FORCEPROP 1 LASTPIN (-8700 3850) $PN 1
J 0
(-8688 3862);
DISPLAY 0.489362 (-8688 3862);
PAINT MONO (-8688 3862);
FORCEPROP 1 LASTPIN (-8500 3850) $PN 2
J 0
(-8538 3862);
DISPLAY 0.489362 (-8538 3862);
PAINT MONO (-8538 3862);
FORCEPROP 1 LAST WATTAGE 1/16W
J 2
(-8350 3875);
DISPLAY 0.489362 (-8350 3875);
PAINT SKYBLUE (-8350 3875);
FORCEPROP 1 LAST MATERIAL CHIP
J 0
(-8475 3800);
DISPLAY 0.489362 (-8475 3800);
PAINT SKYBLUE (-8475 3800);
FORCEPROP 1 LAST PART_NUMBER CS04992FB31
J 0
(-8875 3800);
DISPLAY 0.489362 (-8875 3800);
PAINT SKYBLUE (-8875 3800);
FORCEPROP 1 LAST PACK_TYPE 0402LF
J 0
(-8500 3750);
DISPLAY 0.489362 (-8500 3750);
PAINT SKYBLUE (-8500 3750);
FORCEPROP 1 LAST VALUE 49.9
J 2
(-8600 3925);
DISPLAY 0.489362 (-8600 3925);
PAINT SKYBLUE (-8600 3925);
FORCEPROP 1 LAST TOLERANCE 1%
J 0
(-8800 3875);
DISPLAY 0.489362 (-8800 3875);
PAINT SKYBLUE (-8800 3875);
FORCEPROP 2 LAST CDS_LIB pure_quanta
J 0
(-8600 3850);
DISPLAY INVISIBLE (-8600 3850);
FORCEPROP 1 LAST PATH I504
J 0
(-8650 4000);
DISPLAY 0.978723 (-8650 4000);
PAINT WHITE (-8650 4000);
DISPLAY INVISIBLE (-8650 4000);
FORCEADD UNIVERSAL_GND..1
(-8075 3750);
FORCEPROP 3 LASTPIN (-8075 3800) SIG_NAME GND\g
J 0
(-8065 3810);
DISPLAY 0.659574 (-8065 3810);
PAINT MONO (-8065 3810);
DISPLAY INVISIBLE (-8065 3810);
FORCEPROP 2 LAST CDS_LIB pure_quanta_power
J 0
(-8075 3750);
DISPLAY INVISIBLE (-8075 3750);
FORCEPROP 1 LAST PATH I505
J 0
(-8000 3750);
DISPLAY 0.872340 (-8000 3750);
PAINT AQUA (-8000 3750);
DISPLAY INVISIBLE (-8000 3750);
FORCEPROP 1 LAST HDL_POWER GND
J 1
(-8050 3675);
DISPLAY 0.872340 (-8050 3675);
PAINT GREEN (-8050 3675);
DISPLAY INVISIBLE (-8050 3675);
FORCEADD Q_RES..1
(-8600 3425);
FORCEPROP 1 LAST LOCATION PR227
J 0
(-8650 3475);
DISPLAY 0.489362 (-8650 3475);
PAINT SKYBLUE (-8650 3475);
FORCEPROP 0 LAST $SEC 1
J 0
(-8225 3550);
DISPLAY 0.680851 (-8225 3550);
PAINT MONO (-8225 3550);
DISPLAY INVISIBLE (-8225 3550);
FORCEPROP 0 LAST CDS_SEC 1
J 0
(-8225 3550);
DISPLAY 1.021277 (-8225 3550);
DISPLAY INVISIBLE (-8225 3550);
FORCEPROP 1 LASTPIN (-8700 3425) $PN 1
J 0
(-8688 3437);
DISPLAY 0.489362 (-8688 3437);
PAINT MONO (-8688 3437);
FORCEPROP 1 LASTPIN (-8500 3425) $PN 2
J 0
(-8538 3437);
DISPLAY 0.489362 (-8538 3437);
PAINT MONO (-8538 3437);
FORCEPROP 1 LAST WATTAGE 1/16W
J 2
(-8225 3525);
DISPLAY 0.489362 (-8225 3525);
PAINT SKYBLUE (-8225 3525);
FORCEPROP 1 LAST MATERIAL CHIP
J 0
(-8475 3525);
DISPLAY 0.489362 (-8475 3525);
PAINT SKYBLUE (-8475 3525);
FORCEPROP 1 LAST PART_NUMBER CS04992FB31
J 0
(-8475 3475);
DISPLAY 0.489362 (-8475 3475);
PAINT SKYBLUE (-8475 3475);
FORCEPROP 1 LAST PACK_TYPE 0402LF
J 0
(-8300 3425);
DISPLAY 0.489362 (-8300 3425);
PAINT SKYBLUE (-8300 3425);
FORCEPROP 1 LAST VALUE 49.9
J 2
(-8625 3450);
DISPLAY 0.489362 (-8625 3450);
PAINT SKYBLUE (-8625 3450);
FORCEPROP 1 LAST TOLERANCE 1%
J 0
(-8375 3425);
DISPLAY 0.489362 (-8375 3425);
PAINT SKYBLUE (-8375 3425);
FORCEPROP 2 LAST CDS_LIB pure_quanta
J 0
(-8600 3425);
DISPLAY INVISIBLE (-8600 3425);
FORCEPROP 1 LAST PATH I506
J 0
(-8650 3575);
DISPLAY 0.978723 (-8650 3575);
PAINT WHITE (-8650 3575);
DISPLAY INVISIBLE (-8650 3575);
FORCEADD VCC_CORE..1
(-8075 3575);
FORCEPROP 3 LASTPIN (-8075 3525) SIG_NAME PVDDIO_P1\g
J 0
(-8065 3535);
DISPLAY 0.659574 (-8065 3535);
PAINT MONO (-8065 3535);
DISPLAY INVISIBLE (-8065 3535);
FORCEPROP 1 LAST HDL_POWER PVDDIO_P1
J 1
(-8075 3625);
DISPLAY 0.489362 (-8075 3625);
PAINT GREEN (-8075 3625);
FORCEPROP 2 LAST CDS_LIB pure_quanta_power
J 0
(-8075 3575);
DISPLAY INVISIBLE (-8075 3575);
FORCEPROP 1 LAST PATH I507
J 0
(-8025 3600);
DISPLAY 0.872340 (-8025 3600);
PAINT AQUA (-8025 3600);
DISPLAY INVISIBLE (-8025 3600);
FORCEADD Q_RES..1
(-8625 2750);
FORCEPROP 1 LAST LOCATION PR460
J 0
(-8675 2800);
DISPLAY 0.489362 (-8675 2800);
PAINT SKYBLUE (-8675 2800);
FORCEPROP 0 LAST $SEC 1
J 0
(-8250 2875);
DISPLAY 0.680851 (-8250 2875);
PAINT MONO (-8250 2875);
DISPLAY INVISIBLE (-8250 2875);
FORCEPROP 0 LAST CDS_SEC 1
J 0
(-8250 2875);
DISPLAY 1.021277 (-8250 2875);
DISPLAY INVISIBLE (-8250 2875);
FORCEPROP 1 LASTPIN (-8725 2750) $PN 1
J 0
(-8713 2762);
DISPLAY 0.489362 (-8713 2762);
PAINT MONO (-8713 2762);
FORCEPROP 1 LASTPIN (-8525 2750) $PN 2
J 0
(-8563 2762);
DISPLAY 0.489362 (-8563 2762);
PAINT MONO (-8563 2762);
FORCEPROP 1 LAST WATTAGE 1/16W
J 2
(-8400 2775);
DISPLAY 0.489362 (-8400 2775);
PAINT SKYBLUE (-8400 2775);
FORCEPROP 1 LAST MATERIAL CHIP
J 0
(-8500 2725);
DISPLAY 0.489362 (-8500 2725);
PAINT SKYBLUE (-8500 2725);
FORCEPROP 1 LAST PART_NUMBER CS04992FB31
J 0
(-8875 2700);
DISPLAY 0.489362 (-8875 2700);
PAINT SKYBLUE (-8875 2700);
FORCEPROP 1 LAST PACK_TYPE 0402LF
J 0
(-8525 2675);
DISPLAY 0.489362 (-8525 2675);
PAINT SKYBLUE (-8525 2675);
FORCEPROP 1 LAST VALUE 49.9
J 2
(-8650 2775);
DISPLAY 0.489362 (-8650 2775);
PAINT SKYBLUE (-8650 2775);
FORCEPROP 1 LAST TOLERANCE 1%
J 0
(-8750 2775);
DISPLAY 0.489362 (-8750 2775);
PAINT SKYBLUE (-8750 2775);
FORCEPROP 2 LAST CDS_LIB pure_quanta
J 0
(-8625 2750);
DISPLAY INVISIBLE (-8625 2750);
FORCEPROP 1 LAST PATH I508
J 0
(-8675 2900);
DISPLAY 0.978723 (-8675 2900);
PAINT WHITE (-8675 2900);
DISPLAY INVISIBLE (-8675 2900);
FORCEADD UNIVERSAL_GND..1
(-8100 2650);
FORCEPROP 3 LASTPIN (-8100 2700) SIG_NAME GND\g
J 0
(-8090 2710);
DISPLAY 0.659574 (-8090 2710);
PAINT MONO (-8090 2710);
DISPLAY INVISIBLE (-8090 2710);
FORCEPROP 2 LAST CDS_LIB pure_quanta_power
J 0
(-8100 2650);
DISPLAY INVISIBLE (-8100 2650);
FORCEPROP 1 LAST PATH I509
J 0
(-8025 2650);
DISPLAY 0.872340 (-8025 2650);
PAINT AQUA (-8025 2650);
DISPLAY INVISIBLE (-8025 2650);
FORCEPROP 1 LAST HDL_POWER GND
J 1
(-8075 2575);
DISPLAY 0.872340 (-8075 2575);
PAINT GREEN (-8075 2575);
DISPLAY INVISIBLE (-8075 2575);
FORCEADD OFFPAGE..4
(-3900 2575);
FORCEPROP 2 LAST $XR0 199 
J 0
(-3714 2575);
DISPLAY 0.638298 (-3714 2575);
PAINT MONO (-3714 2575);
FORCEPROP 2 LAST CDS_LIB standard
J 0
(-3900 2575);
DISPLAY INVISIBLE (-3900 2575);
FORCEPROP 1 LAST OFFPAGE TRUE
J 0
(-3575 2450);
DISPLAY 0.872340 (-3575 2450);
PAINT GREEN (-3575 2450);
DISPLAY INVISIBLE (-3575 2450);
FORCEPROP 1 LAST COMMENT_BODY TRUE
J 0
(-3925 2475);
DISPLAY 0.872340 (-3925 2475);
PAINT GREEN (-3925 2475);
DISPLAY INVISIBLE (-3925 2475);
FORCEPROP 2 LAST PATH I512
J 0
(-3700 2625);
DISPLAY 1.021277 (-3700 2625);
DISPLAY INVISIBLE (-3700 2625);
FORCEADD OFFPAGE..2
(-3900 2075);
FORCEPROP 2 LAST $XR0 198 
J 0
(-3711 2075);
DISPLAY 0.638298 (-3711 2075);
PAINT MONO (-3711 2075);
FORCEPROP 2 LAST PATH I513
J 0
(-3700 2125);
DISPLAY 1.021277 (-3700 2125);
DISPLAY INVISIBLE (-3700 2125);
FORCEPROP 1 LAST COMMENT_BODY TRUE
J 0
(-3945 1980);
DISPLAY 0.872340 (-3945 1980);
PAINT GREEN (-3945 1980);
DISPLAY INVISIBLE (-3945 1980);
FORCEPROP 1 LAST OFFPAGE TRUE
J 0
(-3575 1950);
DISPLAY 0.872340 (-3575 1950);
PAINT GREEN (-3575 1950);
DISPLAY INVISIBLE (-3575 1950);
FORCEPROP 2 LAST CDS_LIB standard
J 0
(-3900 2075);
DISPLAY INVISIBLE (-3900 2075);
FORCEADD OFFPAGE..4
(-3900 1975);
FORCEPROP 2 LAST $XR0 198 
J 0
(-3714 1975);
DISPLAY 0.638298 (-3714 1975);
PAINT MONO (-3714 1975);
FORCEPROP 2 LAST PATH I514
J 0
(-3700 2025);
DISPLAY 1.021277 (-3700 2025);
DISPLAY INVISIBLE (-3700 2025);
FORCEPROP 1 LAST COMMENT_BODY TRUE
J 0
(-3925 1875);
DISPLAY 0.872340 (-3925 1875);
PAINT GREEN (-3925 1875);
DISPLAY INVISIBLE (-3925 1875);
FORCEPROP 1 LAST OFFPAGE TRUE
J 0
(-3575 1850);
DISPLAY 0.872340 (-3575 1850);
PAINT GREEN (-3575 1850);
DISPLAY INVISIBLE (-3575 1850);
FORCEPROP 2 LAST CDS_LIB standard
J 0
(-3900 1975);
DISPLAY INVISIBLE (-3900 1975);
FORCEADD OFFPAGE..2
(-3900 2675);
FORCEPROP 2 LAST $XR0 199 
J 0
(-3711 2675);
DISPLAY 0.638298 (-3711 2675);
PAINT MONO (-3711 2675);
FORCEPROP 2 LAST CDS_LIB standard
J 0
(-3900 2675);
DISPLAY INVISIBLE (-3900 2675);
FORCEPROP 1 LAST OFFPAGE TRUE
J 0
(-3575 2550);
DISPLAY 0.872340 (-3575 2550);
PAINT GREEN (-3575 2550);
DISPLAY INVISIBLE (-3575 2550);
FORCEPROP 1 LAST COMMENT_BODY TRUE
J 0
(-3945 2580);
DISPLAY 0.872340 (-3945 2580);
PAINT GREEN (-3945 2580);
DISPLAY INVISIBLE (-3945 2580);
FORCEPROP 2 LAST PATH I517
J 0
(-3700 2725);
DISPLAY 1.021277 (-3700 2725);
DISPLAY INVISIBLE (-3700 2725);
FORCEADD OFFPAGE..2
(-3900 5375);
FORCEPROP 2 LAST $XR0 194 
J 0
(-3711 5375);
DISPLAY 0.638298 (-3711 5375);
PAINT MONO (-3711 5375);
FORCEPROP 2 LAST PATH I520
J 0
(-3575 5425);
DISPLAY 1.021277 (-3575 5425);
DISPLAY INVISIBLE (-3575 5425);
FORCEPROP 2 LAST CDS_LIB standard
J 0
(-3900 5375);
DISPLAY INVISIBLE (-3900 5375);
FORCEPROP 1 LAST OFFPAGE TRUE
J 0
(-3575 5250);
DISPLAY 0.872340 (-3575 5250);
PAINT GREEN (-3575 5250);
DISPLAY INVISIBLE (-3575 5250);
FORCEPROP 1 LAST COMMENT_BODY TRUE
J 0
(-3945 5280);
DISPLAY 0.872340 (-3945 5280);
PAINT GREEN (-3945 5280);
DISPLAY INVISIBLE (-3945 5280);
FORCEADD OFFPAGE..4
(-3900 5275);
FORCEPROP 2 LAST $XR0 194 
J 0
(-3714 5275);
DISPLAY 0.638298 (-3714 5275);
PAINT MONO (-3714 5275);
FORCEPROP 2 LAST PATH I521
J 0
(-3575 5325);
DISPLAY 1.021277 (-3575 5325);
DISPLAY INVISIBLE (-3575 5325);
FORCEPROP 2 LAST CDS_LIB standard
J 0
(-3900 5275);
DISPLAY INVISIBLE (-3900 5275);
FORCEPROP 1 LAST OFFPAGE TRUE
J 0
(-3575 5150);
DISPLAY 0.872340 (-3575 5150);
PAINT GREEN (-3575 5150);
DISPLAY INVISIBLE (-3575 5150);
FORCEPROP 1 LAST COMMENT_BODY TRUE
J 0
(-3925 5175);
DISPLAY 0.872340 (-3925 5175);
PAINT GREEN (-3925 5175);
DISPLAY INVISIBLE (-3925 5175);
FORCEADD OFFPAGE..2
(-3875 5075);
FORCEPROP 2 LAST $XR0 194 
J 0
(-3686 5075);
DISPLAY 0.638298 (-3686 5075);
PAINT MONO (-3686 5075);
FORCEPROP 2 LAST PATH I522
J 0
(-3675 5125);
DISPLAY 1.021277 (-3675 5125);
DISPLAY INVISIBLE (-3675 5125);
FORCEPROP 1 LAST COMMENT_BODY TRUE
J 0
(-3920 4980);
DISPLAY 0.872340 (-3920 4980);
PAINT GREEN (-3920 4980);
DISPLAY INVISIBLE (-3920 4980);
FORCEPROP 1 LAST OFFPAGE TRUE
J 0
(-3550 4950);
DISPLAY 0.872340 (-3550 4950);
PAINT GREEN (-3550 4950);
DISPLAY INVISIBLE (-3550 4950);
FORCEPROP 2 LAST CDS_LIB standard
J 0
(-3875 5075);
DISPLAY INVISIBLE (-3875 5075);
FORCEADD OFFPAGE..4
(-3875 4975);
FORCEPROP 2 LAST $XR0 194 
J 0
(-3689 4975);
DISPLAY 0.638298 (-3689 4975);
PAINT MONO (-3689 4975);
FORCEPROP 2 LAST PATH I523
J 0
(-3675 5025);
DISPLAY 1.021277 (-3675 5025);
DISPLAY INVISIBLE (-3675 5025);
FORCEPROP 1 LAST COMMENT_BODY TRUE
J 0
(-3900 4875);
DISPLAY 0.872340 (-3900 4875);
PAINT GREEN (-3900 4875);
DISPLAY INVISIBLE (-3900 4875);
FORCEPROP 1 LAST OFFPAGE TRUE
J 0
(-3550 4850);
DISPLAY 0.872340 (-3550 4850);
PAINT GREEN (-3550 4850);
DISPLAY INVISIBLE (-3550 4850);
FORCEPROP 2 LAST CDS_LIB standard
J 0
(-3875 4975);
DISPLAY INVISIBLE (-3875 4975);
FORCEADD OFFPAGE..2
(-3900 4775);
FORCEPROP 2 LAST $XR0 195 
J 0
(-3711 4775);
DISPLAY 0.638298 (-3711 4775);
PAINT MONO (-3711 4775);
FORCEPROP 2 LAST PATH I524
J 0
(-3700 4825);
DISPLAY 1.021277 (-3700 4825);
DISPLAY INVISIBLE (-3700 4825);
FORCEPROP 2 LAST CDS_LIB standard
J 0
(-3900 4775);
DISPLAY INVISIBLE (-3900 4775);
FORCEPROP 1 LAST OFFPAGE TRUE
J 0
(-3575 4650);
DISPLAY 0.872340 (-3575 4650);
PAINT GREEN (-3575 4650);
DISPLAY INVISIBLE (-3575 4650);
FORCEPROP 1 LAST COMMENT_BODY TRUE
J 0
(-3945 4680);
DISPLAY 0.872340 (-3945 4680);
PAINT GREEN (-3945 4680);
DISPLAY INVISIBLE (-3945 4680);
FORCEADD OFFPAGE..4
(-3900 4675);
FORCEPROP 2 LAST $XR0 195 
J 0
(-3714 4675);
DISPLAY 0.638298 (-3714 4675);
PAINT MONO (-3714 4675);
FORCEPROP 2 LAST PATH I525
J 0
(-3700 4725);
DISPLAY 1.021277 (-3700 4725);
DISPLAY INVISIBLE (-3700 4725);
FORCEPROP 2 LAST CDS_LIB standard
J 0
(-3900 4675);
DISPLAY INVISIBLE (-3900 4675);
FORCEPROP 1 LAST OFFPAGE TRUE
J 0
(-3575 4550);
DISPLAY 0.872340 (-3575 4550);
PAINT GREEN (-3575 4550);
DISPLAY INVISIBLE (-3575 4550);
FORCEPROP 1 LAST COMMENT_BODY TRUE
J 0
(-3925 4575);
DISPLAY 0.872340 (-3925 4575);
PAINT GREEN (-3925 4575);
DISPLAY INVISIBLE (-3925 4575);
FORCEADD OFFPAGE..2
(-3900 4475);
FORCEPROP 2 LAST $XR0 195 
J 0
(-3711 4475);
DISPLAY 0.638298 (-3711 4475);
PAINT MONO (-3711 4475);
FORCEPROP 2 LAST PATH I526
J 0
(-3700 4525);
DISPLAY 1.021277 (-3700 4525);
DISPLAY INVISIBLE (-3700 4525);
FORCEPROP 2 LAST CDS_LIB standard
J 0
(-3900 4475);
DISPLAY INVISIBLE (-3900 4475);
FORCEPROP 1 LAST OFFPAGE TRUE
J 0
(-3575 4350);
DISPLAY 0.872340 (-3575 4350);
PAINT GREEN (-3575 4350);
DISPLAY INVISIBLE (-3575 4350);
FORCEPROP 1 LAST COMMENT_BODY TRUE
J 0
(-3945 4380);
DISPLAY 0.872340 (-3945 4380);
PAINT GREEN (-3945 4380);
DISPLAY INVISIBLE (-3945 4380);
FORCEADD OFFPAGE..4
(-3900 4375);
FORCEPROP 2 LAST $XR0 195 
J 0
(-3714 4375);
DISPLAY 0.638298 (-3714 4375);
PAINT MONO (-3714 4375);
FORCEPROP 2 LAST PATH I527
J 0
(-3700 4425);
DISPLAY 1.021277 (-3700 4425);
DISPLAY INVISIBLE (-3700 4425);
FORCEPROP 2 LAST CDS_LIB standard
J 0
(-3900 4375);
DISPLAY INVISIBLE (-3900 4375);
FORCEPROP 1 LAST OFFPAGE TRUE
J 0
(-3575 4250);
DISPLAY 0.872340 (-3575 4250);
PAINT GREEN (-3575 4250);
DISPLAY INVISIBLE (-3575 4250);
FORCEPROP 1 LAST COMMENT_BODY TRUE
J 0
(-3925 4275);
DISPLAY 0.872340 (-3925 4275);
PAINT GREEN (-3925 4275);
DISPLAY INVISIBLE (-3925 4275);
FORCEADD OFFPAGE..2
(-3900 4175);
FORCEPROP 2 LAST $XR0 196 
J 0
(-3711 4175);
DISPLAY 0.638298 (-3711 4175);
PAINT MONO (-3711 4175);
FORCEPROP 2 LAST PATH I532
J 0
(-3700 4225);
DISPLAY 1.021277 (-3700 4225);
DISPLAY INVISIBLE (-3700 4225);
FORCEPROP 2 LAST CDS_LIB standard
J 0
(-3900 4175);
DISPLAY INVISIBLE (-3900 4175);
FORCEPROP 1 LAST OFFPAGE TRUE
J 0
(-3575 4050);
DISPLAY 0.872340 (-3575 4050);
PAINT GREEN (-3575 4050);
DISPLAY INVISIBLE (-3575 4050);
FORCEPROP 1 LAST COMMENT_BODY TRUE
J 0
(-3945 4080);
DISPLAY 0.872340 (-3945 4080);
PAINT GREEN (-3945 4080);
DISPLAY INVISIBLE (-3945 4080);
FORCEADD OFFPAGE..4
(-3900 4075);
FORCEPROP 2 LAST $XR0 196 
J 0
(-3714 4075);
DISPLAY 0.638298 (-3714 4075);
PAINT MONO (-3714 4075);
FORCEPROP 2 LAST PATH I533
J 0
(-3700 4125);
DISPLAY 1.021277 (-3700 4125);
DISPLAY INVISIBLE (-3700 4125);
FORCEPROP 2 LAST CDS_LIB standard
J 0
(-3900 4075);
DISPLAY INVISIBLE (-3900 4075);
FORCEPROP 1 LAST OFFPAGE TRUE
J 0
(-3575 3950);
DISPLAY 0.872340 (-3575 3950);
PAINT GREEN (-3575 3950);
DISPLAY INVISIBLE (-3575 3950);
FORCEPROP 1 LAST COMMENT_BODY TRUE
J 0
(-3925 3975);
DISPLAY 0.872340 (-3925 3975);
PAINT GREEN (-3925 3975);
DISPLAY INVISIBLE (-3925 3975);
FORCEADD OFFPAGE..2
(-3900 3875);
FORCEPROP 2 LAST $XR0 196 
J 0
(-3711 3875);
DISPLAY 0.638298 (-3711 3875);
PAINT MONO (-3711 3875);
FORCEPROP 2 LAST PATH I534
J 0
(-3700 3925);
DISPLAY 1.021277 (-3700 3925);
DISPLAY INVISIBLE (-3700 3925);
FORCEPROP 2 LAST CDS_LIB standard
J 0
(-3900 3875);
DISPLAY INVISIBLE (-3900 3875);
FORCEPROP 1 LAST OFFPAGE TRUE
J 0
(-3575 3750);
DISPLAY 0.872340 (-3575 3750);
PAINT GREEN (-3575 3750);
DISPLAY INVISIBLE (-3575 3750);
FORCEPROP 1 LAST COMMENT_BODY TRUE
J 0
(-3945 3780);
DISPLAY 0.872340 (-3945 3780);
PAINT GREEN (-3945 3780);
DISPLAY INVISIBLE (-3945 3780);
FORCEADD OFFPAGE..4
(-3925 3775);
FORCEPROP 2 LAST $XR0 196 
J 0
(-3739 3775);
DISPLAY 0.638298 (-3739 3775);
PAINT MONO (-3739 3775);
FORCEPROP 2 LAST PATH I535
J 0
(-3725 3825);
DISPLAY 1.021277 (-3725 3825);
DISPLAY INVISIBLE (-3725 3825);
FORCEPROP 2 LAST CDS_LIB standard
J 0
(-3925 3775);
DISPLAY INVISIBLE (-3925 3775);
FORCEPROP 1 LAST OFFPAGE TRUE
J 0
(-3600 3650);
DISPLAY 0.872340 (-3600 3650);
PAINT GREEN (-3600 3650);
DISPLAY INVISIBLE (-3600 3650);
FORCEPROP 1 LAST COMMENT_BODY TRUE
J 0
(-3950 3675);
DISPLAY 0.872340 (-3950 3675);
PAINT GREEN (-3950 3675);
DISPLAY INVISIBLE (-3950 3675);
FORCEADD OFFPAGE..4
(-3900 2275);
FORCEPROP 2 LAST $XR0 198 
J 0
(-3714 2275);
DISPLAY 0.638298 (-3714 2275);
PAINT MONO (-3714 2275);
FORCEPROP 2 LAST PATH I536
J 0
(-3700 2325);
DISPLAY 1.021277 (-3700 2325);
DISPLAY INVISIBLE (-3700 2325);
FORCEPROP 1 LAST COMMENT_BODY TRUE
J 0
(-3925 2175);
DISPLAY 0.872340 (-3925 2175);
PAINT GREEN (-3925 2175);
DISPLAY INVISIBLE (-3925 2175);
FORCEPROP 1 LAST OFFPAGE TRUE
J 0
(-3575 2150);
DISPLAY 0.872340 (-3575 2150);
PAINT GREEN (-3575 2150);
DISPLAY INVISIBLE (-3575 2150);
FORCEPROP 2 LAST CDS_LIB standard
J 0
(-3900 2275);
DISPLAY INVISIBLE (-3900 2275);
FORCEADD OFFPAGE..2
(-3900 2375);
FORCEPROP 2 LAST $XR0 198 
J 0
(-3711 2375);
DISPLAY 0.638298 (-3711 2375);
PAINT MONO (-3711 2375);
FORCEPROP 2 LAST PATH I537
J 0
(-3700 2425);
DISPLAY 1.021277 (-3700 2425);
DISPLAY INVISIBLE (-3700 2425);
FORCEPROP 1 LAST COMMENT_BODY TRUE
J 0
(-3945 2280);
DISPLAY 0.872340 (-3945 2280);
PAINT GREEN (-3945 2280);
DISPLAY INVISIBLE (-3945 2280);
FORCEPROP 1 LAST OFFPAGE TRUE
J 0
(-3575 2250);
DISPLAY 0.872340 (-3575 2250);
PAINT GREEN (-3575 2250);
DISPLAY INVISIBLE (-3575 2250);
FORCEPROP 2 LAST CDS_LIB standard
J 0
(-3900 2375);
DISPLAY INVISIBLE (-3900 2375);
FORCEADD OFFPAGE..2
(-3900 2975);
FORCEPROP 2 LAST $XR0 199 
J 0
(-3711 2975);
DISPLAY 0.638298 (-3711 2975);
PAINT MONO (-3711 2975);
FORCEPROP 2 LAST PATH I538
J 0
(-3700 3025);
DISPLAY 1.021277 (-3700 3025);
DISPLAY INVISIBLE (-3700 3025);
FORCEPROP 2 LAST CDS_LIB standard
J 0
(-3900 2975);
DISPLAY INVISIBLE (-3900 2975);
FORCEPROP 1 LAST OFFPAGE TRUE
J 0
(-3575 2850);
DISPLAY 0.872340 (-3575 2850);
PAINT GREEN (-3575 2850);
DISPLAY INVISIBLE (-3575 2850);
FORCEPROP 1 LAST COMMENT_BODY TRUE
J 0
(-3945 2880);
DISPLAY 0.872340 (-3945 2880);
PAINT GREEN (-3945 2880);
DISPLAY INVISIBLE (-3945 2880);
FORCEADD OFFPAGE..4
(-3900 2875);
FORCEPROP 2 LAST $XR0 199 
J 0
(-3714 2875);
DISPLAY 0.638298 (-3714 2875);
PAINT MONO (-3714 2875);
FORCEPROP 2 LAST PATH I539
J 0
(-3700 2925);
DISPLAY 1.021277 (-3700 2925);
DISPLAY INVISIBLE (-3700 2925);
FORCEPROP 2 LAST CDS_LIB standard
J 0
(-3900 2875);
DISPLAY INVISIBLE (-3900 2875);
FORCEPROP 1 LAST OFFPAGE TRUE
J 0
(-3575 2750);
DISPLAY 0.872340 (-3575 2750);
PAINT GREEN (-3575 2750);
DISPLAY INVISIBLE (-3575 2750);
FORCEPROP 1 LAST COMMENT_BODY TRUE
J 0
(-3925 2775);
DISPLAY 0.872340 (-3925 2775);
PAINT GREEN (-3925 2775);
DISPLAY INVISIBLE (-3925 2775);
FORCEADD UNIVERSAL_GND..1
(-3825 3400);
FORCEPROP 3 LASTPIN (-3825 3450) SIG_NAME GND\g
J 0
(-3815 3460);
DISPLAY 0.659574 (-3815 3460);
PAINT MONO (-3815 3460);
DISPLAY INVISIBLE (-3815 3460);
FORCEPROP 2 LAST CDS_LIB pure_quanta_power
J 0
(-3825 3400);
DISPLAY INVISIBLE (-3825 3400);
FORCEPROP 1 LAST PATH I540
J 0
(-3750 3400);
DISPLAY 0.872340 (-3750 3400);
PAINT AQUA (-3750 3400);
DISPLAY INVISIBLE (-3750 3400);
FORCEPROP 1 LAST HDL_POWER GND
J 1
(-3800 3325);
DISPLAY 0.872340 (-3800 3325);
PAINT GREEN (-3800 3325);
DISPLAY INVISIBLE (-3800 3325);
FORCEADD Q_RES..1
(-4275 3475);
FORCEPROP 1 LAST LOCATION PR533
J 0
(-4325 3525);
DISPLAY 0.489362 (-4325 3525);
PAINT SKYBLUE (-4325 3525);
FORCEPROP 0 LAST $SEC 1
J 0
(-4325 3550);
DISPLAY 0.680851 (-4325 3550);
PAINT MONO (-4325 3550);
DISPLAY INVISIBLE (-4325 3550);
FORCEPROP 0 LAST CDS_SEC 1
J 0
(-4325 3550);
DISPLAY 0.680851 (-4325 3550);
DISPLAY INVISIBLE (-4325 3550);
FORCEPROP 1 LASTPIN (-4375 3475) $PN 1
J 0
(-4363 3487);
DISPLAY 0.787234 (-4363 3487);
PAINT MONO (-4363 3487);
DISPLAY INVISIBLE (-4363 3487);
FORCEPROP 1 LASTPIN (-4175 3475) $PN 2
J 0
(-4213 3487);
DISPLAY 0.787234 (-4213 3487);
PAINT MONO (-4213 3487);
DISPLAY INVISIBLE (-4213 3487);
FORCEPROP 1 LAST PART_NUMBER CS00002JB38
J 0
(-4950 3425);
DISPLAY 0.489362 (-4950 3425);
PAINT SKYBLUE (-4950 3425);
FORCEPROP 1 LAST PACK_TYPE 0402LF
J 0
(-4175 3425);
DISPLAY 0.489362 (-4175 3425);
PAINT SKYBLUE (-4175 3425);
FORCEPROP 1 LAST TOLERANCE 5%
J 0
(-4250 3425);
DISPLAY 0.489362 (-4250 3425);
PAINT SKYBLUE (-4250 3425);
FORCEPROP 1 LAST WATTAGE 1/16W
J 2
(-4350 3425);
DISPLAY 0.489362 (-4350 3425);
PAINT SKYBLUE (-4350 3425);
FORCEPROP 1 LAST MATERIAL CHIP
J 0
(-4600 3425);
DISPLAY 0.489362 (-4600 3425);
PAINT SKYBLUE (-4600 3425);
FORCEPROP 1 LAST VALUE 0
J 2
(-4275 3425);
DISPLAY 0.489362 (-4275 3425);
PAINT SKYBLUE (-4275 3425);
FORCEPROP 2 LAST CDS_LIB pure_quanta
J 0
(-4275 3475);
DISPLAY INVISIBLE (-4275 3475);
FORCEPROP 1 LAST PATH I541
J 0
(-4325 3625);
DISPLAY 0.978723 (-4325 3625);
PAINT WHITE (-4325 3625);
DISPLAY INVISIBLE (-4325 3625);
FORCEADD UNIVERSAL_GND..1
(-3825 3100);
FORCEPROP 3 LASTPIN (-3825 3150) SIG_NAME GND\g
J 0
(-3815 3160);
DISPLAY 0.659574 (-3815 3160);
PAINT MONO (-3815 3160);
DISPLAY INVISIBLE (-3815 3160);
FORCEPROP 2 LAST CDS_LIB pure_quanta_power
J 0
(-3825 3100);
DISPLAY INVISIBLE (-3825 3100);
FORCEPROP 1 LAST PATH I542
J 0
(-3750 3100);
DISPLAY 0.872340 (-3750 3100);
PAINT AQUA (-3750 3100);
DISPLAY INVISIBLE (-3750 3100);
FORCEPROP 1 LAST HDL_POWER GND
J 1
(-3800 3025);
DISPLAY 0.872340 (-3800 3025);
PAINT GREEN (-3800 3025);
DISPLAY INVISIBLE (-3800 3025);
FORCEADD Q_RES..1
(-4275 3175);
FORCEPROP 1 LAST LOCATION PR12
J 0
(-4325 3225);
DISPLAY 0.489362 (-4325 3225);
PAINT SKYBLUE (-4325 3225);
FORCEPROP 0 LAST $SEC 1
J 0
(-4325 3275);
DISPLAY 0.680851 (-4325 3275);
PAINT MONO (-4325 3275);
DISPLAY INVISIBLE (-4325 3275);
FORCEPROP 0 LAST CDS_SEC 1
J 0
(-4325 3275);
DISPLAY 1.021277 (-4325 3275);
DISPLAY INVISIBLE (-4325 3275);
FORCEPROP 1 LASTPIN (-4375 3175) $PN 1
J 0
(-4363 3187);
DISPLAY 0.489362 (-4363 3187);
PAINT MONO (-4363 3187);
FORCEPROP 1 LASTPIN (-4175 3175) $PN 2
J 0
(-4213 3187);
DISPLAY 0.489362 (-4213 3187);
PAINT MONO (-4213 3187);
FORCEPROP 1 LAST WATTAGE 1/16W
J 2
(-4350 3125);
DISPLAY 0.489362 (-4350 3125);
PAINT SKYBLUE (-4350 3125);
FORCEPROP 1 LAST MATERIAL CHIP
J 0
(-4600 3125);
DISPLAY 0.489362 (-4600 3125);
PAINT SKYBLUE (-4600 3125);
FORCEPROP 1 LAST TOLERANCE 5%
J 0
(-4250 3125);
DISPLAY 0.489362 (-4250 3125);
PAINT SKYBLUE (-4250 3125);
FORCEPROP 1 LAST VALUE 0
J 2
(-4275 3125);
DISPLAY 0.489362 (-4275 3125);
PAINT SKYBLUE (-4275 3125);
FORCEPROP 1 LAST PART_NUMBER CS00002JB38
J 0
(-4950 3125);
DISPLAY 0.489362 (-4950 3125);
PAINT SKYBLUE (-4950 3125);
FORCEPROP 1 LAST PACK_TYPE 0402LF
J 0
(-4175 3125);
DISPLAY 0.489362 (-4175 3125);
PAINT SKYBLUE (-4175 3125);
FORCEPROP 2 LAST CDS_LIB pure_quanta
J 0
(-4275 3175);
DISPLAY INVISIBLE (-4275 3175);
FORCEPROP 1 LAST PATH I543
J 0
(-4325 3325);
DISPLAY 0.978723 (-4325 3325);
PAINT WHITE (-4325 3325);
DISPLAY INVISIBLE (-4325 3325);
FORCEADD UNIVERSAL_GND..1
(-7000 450);
FORCEPROP 3 LASTPIN (-7000 500) SIG_NAME GND\g
J 0
(-6990 510);
DISPLAY 0.659574 (-6990 510);
PAINT MONO (-6990 510);
DISPLAY INVISIBLE (-6990 510);
FORCEPROP 2 LAST CDS_LIB pure_quanta_power
J 0
(-7000 450);
DISPLAY INVISIBLE (-7000 450);
FORCEPROP 1 LAST PATH I544
J 0
(-6925 450);
DISPLAY 0.872340 (-6925 450);
PAINT AQUA (-6925 450);
DISPLAY INVISIBLE (-6925 450);
FORCEPROP 1 LAST HDL_POWER GND
J 1
(-6975 375);
DISPLAY 0.872340 (-6975 375);
PAINT GREEN (-6975 375);
DISPLAY INVISIBLE (-6975 375);
FORCEADD Q_RES..2
(-7000 650);
FORCEPROP 1 LAST LOCATION PR603
J 0
(-6950 775);
DISPLAY 0.489362 (-6950 775);
PAINT SKYBLUE (-6950 775);
FORCEPROP 0 LAST $SEC 1
J 0
(-6950 800);
DISPLAY 0.680851 (-6950 800);
PAINT MONO (-6950 800);
DISPLAY INVISIBLE (-6950 800);
FORCEPROP 0 LAST CDS_SEC 1
J 0
(-6950 800);
DISPLAY 0.680851 (-6950 800);
DISPLAY INVISIBLE (-6950 800);
FORCEPROP 1 LASTPIN (-7000 750) $PN 1
J 0
(-6995 712);
DISPLAY 0.787234 (-6995 712);
PAINT MONO (-6995 712);
DISPLAY INVISIBLE (-6995 712);
FORCEPROP 1 LASTPIN (-7000 550) $PN 2
J 0
(-6995 560);
DISPLAY 0.787234 (-6995 560);
PAINT MONO (-6995 560);
DISPLAY INVISIBLE (-6995 560);
FORCEPROP 1 LAST WATTAGE 1/16W
J 0
(-6950 625);
DISPLAY 0.489362 (-6950 625);
PAINT SKYBLUE (-6950 625);
FORCEPROP 1 LAST MATERIAL EMPTY
J 0
(-6950 575);
DISPLAY 0.489362 (-6950 575);
PAINT RED (-6950 575);
FORCEPROP 1 LAST TOLERANCE 1%
J 0
(-6950 675);
DISPLAY 0.489362 (-6950 675);
PAINT SKYBLUE (-6950 675);
FORCEPROP 1 LAST VALUE 4.99K
J 0
(-6950 725);
DISPLAY 0.489362 (-6950 725);
PAINT SKYBLUE (-6950 725);
FORCEPROP 1 LAST PART_NUMBER CS24992FB07
J 0
(-6950 525);
DISPLAY 0.489362 (-6950 525);
PAINT SKYBLUE (-6950 525);
FORCEPROP 1 LAST PACK_TYPE 0402LF
J 0
(-6950 475);
DISPLAY 0.489362 (-6950 475);
PAINT SKYBLUE (-6950 475);
FORCEPROP 2 LAST CDS_LIB pure_quanta
J 0
(-7000 650);
DISPLAY INVISIBLE (-7000 650);
FORCEPROP 1 LAST PATH I545
J 0
(-6950 825);
DISPLAY 0.978723 (-6950 825);
PAINT WHITE (-6950 825);
DISPLAY INVISIBLE (-6950 825);
FORCEADD DNS..1
(-10125 6225);
PAINT RED (-10125 6225);
FORCEPROP 2 LAST CDS_LIB mstr_misc
J 0
(-10125 6225);
DISPLAY INVISIBLE (-10125 6225);
FORCEPROP 1 LAST COMMENT_BODY TRUE
R 1
J 0
(-10050 6000);
DISPLAY 0.872340 (-10050 6000);
PAINT GREEN (-10050 6000);
DISPLAY INVISIBLE (-10050 6000);
FORCEADD DNS..1
(-9575 6225);
PAINT RED (-9575 6225);
FORCEPROP 2 LAST CDS_LIB mstr_misc
J 0
(-9575 6225);
DISPLAY INVISIBLE (-9575 6225);
FORCEPROP 1 LAST COMMENT_BODY TRUE
R 1
J 0
(-9500 6000);
DISPLAY 0.872340 (-9500 6000);
PAINT GREEN (-9500 6000);
DISPLAY INVISIBLE (-9500 6000);
FORCEADD DNS..1
(-7175 1300);
PAINT RED (-7175 1300);
FORCEPROP 2 LAST CDS_LIB mstr_misc
J 0
(-7175 1300);
DISPLAY INVISIBLE (-7175 1300);
FORCEPROP 1 LAST COMMENT_BODY TRUE
R 1
J 0
(-7100 1075);
DISPLAY 0.872340 (-7100 1075);
PAINT GREEN (-7100 1075);
DISPLAY INVISIBLE (-7100 1075);
FORCEADD DNS..1
(-9375 6225);
PAINT RED (-9375 6225);
FORCEPROP 2 LAST CDS_LIB mstr_misc
J 0
(-9375 6225);
DISPLAY INVISIBLE (-9375 6225);
FORCEPROP 1 LAST COMMENT_BODY TRUE
R 1
J 0
(-9300 6000);
DISPLAY 0.872340 (-9300 6000);
PAINT GREEN (-9300 6000);
DISPLAY INVISIBLE (-9300 6000);
FORCEADD DNS..1
(-6975 650);
PAINT RED (-6975 650);
FORCEPROP 2 LAST CDS_LIB mstr_misc
J 0
(-6975 650);
DISPLAY INVISIBLE (-6975 650);
FORCEPROP 1 LAST COMMENT_BODY TRUE
R 1
J 0
(-6900 425);
DISPLAY 0.872340 (-6900 425);
PAINT GREEN (-6900 425);
DISPLAY INVISIBLE (-6900 425);
FORCEADD DNS..1
(-10000 5250);
PAINT RED (-10000 5250);
FORCEPROP 2 LAST CDS_LIB mstr_misc
J 0
(-10000 5250);
DISPLAY INVISIBLE (-10000 5250);
FORCEPROP 1 LAST COMMENT_BODY TRUE
R 1
J 0
(-9925 5025);
DISPLAY 0.872340 (-9925 5025);
PAINT GREEN (-9925 5025);
DISPLAY INVISIBLE (-9925 5025);
FORCEADD QUANTA_TITLE_BLOCK_C..1
(-1225 150);
FORCEPROP 0 LAST CDS_CON_LAST_MODIFIED Fri Mar 11 14:53:35 2022
J 0
(-3110 165);
DISPLAY INVISIBLE (-3110 165);
FORCEPROP 1 LAST CUSTOM_TXT_CDS <CON_LAST_MODIFIED>
J 0
(-3110 165);
DISPLAY 0.978723 (-3110 165);
FORCEPROP 2 LAST CUSTOM_TXT_CDS <XR_PAGE_TITLE>
J 0
(-9115 5400);
DISPLAY 0.638298 (-9115 5400);
PAINT PINK (-9115 5400);
DISPLAY INVISIBLE (-9115 5400);
FORCEPROP 1 LAST CUSTOM_TXT_CDS <NAME_2>
J 0
(-4400 200);
FORCEPROP 1 LAST CUSTOM_TXT_CDS <NAME_1>
J 0
(-4400 325);
FORCEPROP 1 LAST CUSTOM_TXT_CDS <Q_NUMBER>
J 0
(-2628 253);
DISPLAY 1.212766 (-2628 253);
FORCEPROP 1 LAST CUSTOM_TXT_CDS <Q_PROJ>
J 0
(-3607 252);
DISPLAY 1.212766 (-3607 252);
FORCEPROP 1 LAST CUSTOM_TXT_CDS <Q_REV>
J 0
(-1409 253);
DISPLAY 1.212766 (-1409 253);
FORCEPROP 1 LAST CUSTOM_TXT_CDS <CON_PAGE_NUM> OF <CON_TOTAL_PAGES>
J 0
(-1671 168);
DISPLAY 0.978723 (-1671 168);
FORCEPROP 1 LAST Q_DEPT BU9
J 1
(-4988 199);
DISPLAY 1.957447 (-4988 199);
PAINT GREEN (-4988 199);
FORCEPROP 1 LAST Q_TITLE PVDDCR_CPU1_P1/PVDDIO_P1 VR CONTROLLER
J 0
(-10525 200);
DISPLAY 2.446809 (-10525 200);
PAINT GREEN (-10525 200);
FORCEPROP 1 LAST CDS_LMAN_SYM_OUTLINE -9475,6775,100,-125
J 0
(-1225 150);
DISPLAY 0.468085 (-1225 150);
PAINT GREEN (-1225 150);
DISPLAY INVISIBLE (-1225 150);
FORCEPROP 2 LAST CDS_LIB pure_quanta
J 0
(-1225 150);
DISPLAY INVISIBLE (-1225 150);
FORCEPROP 2 LAST PAGE_BORDER TRUE
J 0
(-9115 5400);
DISPLAY 0.638298 (-9115 5400);
PAINT PINK (-9115 5400);
DISPLAY INVISIBLE (-9115 5400);
FORCEPROP 1 LAST COMMENT_BODY TRUE
J 0
(-1213 137);
DISPLAY 0.978723 (-1213 137);
PAINT GREEN (-1213 137);
DISPLAY INVISIBLE (-1213 137);
FORCEPROP 2 LAST CDS_XR_PAGE_TITLE CR-193 : @T6G_MB_LIB.T6G(SCH_1):PAGE193
J 0
(-9115 5400);
DISPLAY 0.638298 (-9115 5400);
PAINT PINK (-9115 5400);
DISPLAY INVISIBLE (-9115 5400);
FORCEADD DNS..1
(-9625 5250);
PAINT RED (-9625 5250);
FORCEPROP 2 LAST CDS_LIB mstr_misc
J 0
(-9625 5250);
DISPLAY INVISIBLE (-9625 5250);
FORCEPROP 1 LAST COMMENT_BODY TRUE
R 1
J 0
(-9550 5025);
DISPLAY 0.872340 (-9550 5025);
PAINT GREEN (-9550 5025);
DISPLAY INVISIBLE (-9550 5025);
FORCEADD DNS..1
(-7225 6550);
PAINT RED (-7225 6550);
FORCEPROP 2 LAST CDS_LIB mstr_misc
J 0
(-7225 6550);
DISPLAY INVISIBLE (-7225 6550);
FORCEPROP 1 LAST COMMENT_BODY TRUE
R 1
J 0
(-7150 6325);
DISPLAY 0.872340 (-7150 6325);
PAINT GREEN (-7150 6325);
DISPLAY INVISIBLE (-7150 6325);
FORCEADD DNS..1
(-9750 6225);
PAINT RED (-9750 6225);
FORCEPROP 2 LAST CDS_LIB mstr_misc
J 0
(-9750 6225);
DISPLAY INVISIBLE (-9750 6225);
FORCEPROP 1 LAST COMMENT_BODY TRUE
R 1
J 0
(-9675 6000);
DISPLAY 0.872340 (-9675 6000);
PAINT GREEN (-9675 6000);
DISPLAY INVISIBLE (-9675 6000);
FORCEADD DNS..1
(-9425 5250);
PAINT RED (-9425 5250);
FORCEPROP 2 LAST CDS_LIB mstr_misc
J 0
(-9425 5250);
DISPLAY INVISIBLE (-9425 5250);
FORCEPROP 1 LAST COMMENT_BODY TRUE
R 1
J 0
(-9350 5025);
DISPLAY 0.872340 (-9350 5025);
PAINT GREEN (-9350 5025);
DISPLAY INVISIBLE (-9350 5025);
WIRE 16 -1 (-8450 1275)(-8075 1275);
WIRE 16 -1 (-8450 1275)(-8450 1325);
WIRE 16 -1 (-8500 6525)(-8175 6525);
WIRE 16 -1 (-8500 6525)(-8500 6575);
WIRE 16 -1 (-6650 500)(-6650 575);
WIRE 16 -1 (-7075 1275)(-6525 1275);
WIRE 16 -1 (-4350 800)(-4350 900);
WIRE 16 -1 (-7150 6100)(-6575 6100);
WIRE 16 -1 (-7125 6525)(-6575 6525);
WIRE 16 -1 (-6925 2000)(-6675 2000);
WIRE 16 -1 (-9700 1350)(-9700 1450);
WIRE 16 -1 (-8700 1025)(-8925 1025);
WIRE 16 -1 (-4350 1375)(-4350 1475);
WIRE 16 -1 (-4350 6100)(-4350 6050);
WIRE 16 -1 (-4350 5575)(-4350 5625);
WIRE 16 -1 (-4725 5650)(-4725 5575);
WIRE 16 -1 (-4725 6125)(-4725 6050);
WIRE 16 -1 (-8075 3850)(-8075 3800);
WIRE 16 -1 (-8075 3850)(-8500 3850);
WIRE 16 -1 (-8100 2750)(-8100 2700);
WIRE 16 -1 (-8100 2750)(-8525 2750);
WIRE 16 -1 (-3825 3475)(-3825 3450);
WIRE 16 -1 (-4175 3475)(-3825 3475);
WIRE 16 -1 (-3825 3175)(-3825 3150);
WIRE 16 -1 (-4175 3175)(-3825 3175);
WIRE 16 -1 (-7000 550)(-7000 500);
WIRE 16 -1 (-6375 2975)(-6575 2975);
WIRE 16 -1 (-6575 2900)(-6575 2975);
WIRE 16 -1 (-6575 2900)(-7225 2900);
WIRE 16 -1 (-7225 3000)(-7225 2900);
WIRE 16 -1 (-8850 2900)(-7225 2900);
WIRE 16 -1 (-9900 2900)(-8850 2900);
FORCEPROP 2 LAST SIG_NAME VSENSE_VSS_SENSE_B_P1
J 0
(-9485 2910);
DISPLAY 0.489362 (-9485 2910);
WIRE 16 -1 (-8850 2750)(-8850 2900);
WIRE 16 -1 (-8850 2750)(-8725 2750);
WIRE 16 -1 (-9900 3275)(-8850 3275);
FORCEPROP 2 LAST SIG_NAME VSENSE_PVDDIO_P1_DP
J 0
(-9510 3285);
DISPLAY 0.489362 (-9510 3285);
WIRE 16 -1 (-7775 3275)(-8850 3275);
WIRE 16 -1 (-8850 3275)(-8850 3425);
WIRE 16 -1 (-8850 3425)(-8700 3425);
WIRE 16 -1 (-8075 3525)(-8075 3425);
WIRE 16 -1 (-8075 3425)(-8500 3425);
WIRE 16 -1 (-6375 4075)(-6575 4075);
WIRE 16 -1 (-6575 4000)(-6575 4075);
WIRE 16 -1 (-6575 4000)(-7275 4000);
WIRE 16 -1 (-7275 4100)(-7275 4000);
WIRE 16 -1 (-8850 4000)(-7275 4000);
WIRE 16 -1 (-9900 4000)(-8850 4000);
FORCEPROP 2 LAST SIG_NAME VSENSE_VSS_SENSE_C_P1
J 2
(-9110 4010);
DISPLAY 0.489362 (-9110 4010);
WIRE 16 -1 (-8850 3850)(-8850 4000);
WIRE 16 -1 (-8850 3850)(-8700 3850);
WIRE 16 -1 (-7825 4375)(-8850 4375);
WIRE 16 -1 (-8850 4525)(-8850 4375);
WIRE 16 -1 (-8850 4375)(-9900 4375);
FORCEPROP 2 LAST SIG_NAME VSENSE_PVDDCR_CPU1_P1_DP
J 0
(-9585 4385);
DISPLAY 0.489362 (-9585 4385);
WIRE 16 -1 (-8850 4525)(-8650 4525);
WIRE 16 -1 (-7875 4625)(-7875 4525);
WIRE 16 -1 (-7875 4525)(-8450 4525);
WIRE 17 273 (-2900 4350)(-1300 4350);
WIRE 17 273 (-2900 5400)(-2900 4350);
WIRE 17 273 (-1300 5400)(-1300 4350);
WIRE 17 273 (-2900 5400)(-1300 5400);
WIRE 17 273 (-2900 5450)(-1300 5450);
WIRE 17 273 (-2900 6700)(-2900 5450);
WIRE 17 273 (-1300 6700)(-1300 5450);
WIRE 17 273 (-2900 6700)(-1300 6700);
WIRE 16 -1 (-3375 6450)(-3375 6375);
WIRE 16 -1 (-3375 6375)(-3800 6375);
WIRE 16 -1 (-5025 2375)(-3950 2375);
FORCEPROP 2 LAST SIG_NAME PVDDIO_P1_PWM2
J 0
(-4835 2385);
DISPLAY 0.489362 (-4835 2385);
WIRE 16 -1 (-3950 2275)(-5025 2275);
FORCEPROP 2 LAST SIG_NAME PVDDIO_P1_IMON2
J 0
(-4835 2285);
DISPLAY 0.489362 (-4835 2285);
WIRE 16 -1 (-5025 3875)(-3950 3875);
FORCEPROP 0 LAST SIG_NAME PVDDCR_CPU1_P1_PWM6
J 0
(-4835 3885);
DISPLAY 0.489362 (-4835 3885);
WIRE 16 -1 (-5025 4175)(-3950 4175);
FORCEPROP 0 LAST SIG_NAME PVDDCR_CPU1_P1_PWM5
J 0
(-4835 4185);
DISPLAY 0.489362 (-4835 4185);
WIRE 16 -1 (-5025 4375)(-3950 4375);
FORCEPROP 2 LAST SIG_NAME PVDDCR_CPU1_P1_IMON4
J 0
(-4835 4385);
DISPLAY 0.489362 (-4835 4385);
WIRE 16 -1 (-5025 4975)(-3925 4975);
FORCEPROP 2 LAST SIG_NAME PVDDCR_CPU1_P1_IMON2
J 0
(-4835 4985);
DISPLAY 0.489362 (-4835 4985);
WIRE 16 -1 (-5025 5275)(-3950 5275);
FORCEPROP 2 LAST SIG_NAME PVDDCR_CPU1_P1_IMON1
J 0
(-4835 5285);
DISPLAY 0.489362 (-4835 5285);
WIRE 16 -1 (-5025 5375)(-3950 5375);
FORCEPROP 2 LAST SIG_NAME PVDDCR_CPU1_P1_PWM1
J 0
(-4835 5385);
DISPLAY 0.489362 (-4835 5385);
WIRE 16 -1 (-3950 1975)(-5025 1975);
FORCEPROP 2 LAST SIG_NAME PVDDIO_P1_IMON1
J 0
(-4835 1985);
DISPLAY 0.489362 (-4835 1985);
WIRE 16 -1 (-5025 2075)(-3950 2075);
FORCEPROP 2 LAST SIG_NAME PVDDIO_P1_PWM1
J 0
(-4835 2085);
DISPLAY 0.489362 (-4835 2085);
WIRE 16 -1 (-3950 2575)(-5025 2575);
FORCEPROP 2 LAST SIG_NAME PVDDIO_P1_IMON3
J 0
(-4835 2585);
DISPLAY 0.489362 (-4835 2585);
WIRE 16 -1 (-4350 6375)(-4725 6375);
WIRE 16 -1 (-4000 6375)(-4350 6375);
WIRE 16 -1 (-4350 6300)(-4350 6375);
WIRE 16 -1 (-4725 6375)(-4725 6325);
WIRE 16 -1 (-4725 6375)(-5025 6375);
FORCEPROP 2 LAST SIG_NAME PVDDCR_CPU1_P1_VCC
J 0
(-4860 6385);
DISPLAY 0.489362 (-4860 6385);
FORCEPROP 2 LASTPROP $XRERR UNIQUE?
J 0
(-5100 6385);
DISPLAY 0.638298 (-5100 6385);
PAINT MONO (-5100 6385);
DISPLAY INVISIBLE (-5100 6385);
WIRE 16 -1 (-5025 6075)(-4875 6075);
WIRE 16 -1 (-4875 6075)(-4875 5900);
WIRE 16 -1 (-4875 5900)(-4725 5900);
FORCEPROP 2 LAST SIG_NAME PVDDCR_CPU1_P1_VCCS
J 0
(-4835 5910);
DISPLAY 0.489362 (-4835 5910);
WIRE 16 -1 (-4725 5900)(-4350 5900);
WIRE 16 -1 (-4725 5900)(-4725 5850);
WIRE 16 -1 (-3725 5900)(-4350 5900);
WIRE 16 -1 (-4350 5825)(-4350 5900);
WIRE 16 -1 (-7325 6525)(-7550 6525);
WIRE 16 -1 (-7550 6375)(-7550 6525);
WIRE 16 -1 (-7550 6525)(-7975 6525);
WIRE 16 -1 (-7550 6375)(-6375 6375);
FORCEPROP 2 LAST SIG_NAME PWRGD_PVDDCR_CPU1_P1_R
J 0
(-6985 6385);
DISPLAY 0.489362 (-6985 6385);
FORCEPROP 2 LASTPROP $XRERR UNIQUE?
J 0
(-7225 6385);
DISPLAY 0.638298 (-7225 6385);
PAINT MONO (-7225 6385);
DISPLAY INVISIBLE (-7225 6385);
WIRE 16 -1 (-7550 6375)(-7975 6375);
WIRE 16 -1 (-7350 6100)(-7550 6100);
WIRE 16 -1 (-7550 6225)(-7550 6100);
WIRE 16 -1 (-7550 6225)(-6375 6225);
FORCEPROP 2 LAST SIG_NAME PVDDCR_CPU1_P1_EN_R
J 0
(-6985 6235);
DISPLAY 0.489362 (-6985 6235);
FORCEPROP 2 LASTPROP $XRERR UNIQUE?
J 0
(-7225 6235);
DISPLAY 0.638298 (-7225 6235);
PAINT MONO (-7225 6235);
DISPLAY INVISIBLE (-7225 6235);
WIRE 16 -1 (-7975 6225)(-7550 6225);
WIRE 16 -1 (-6375 5475)(-7975 5475);
FORCEPROP 2 LAST SIG_NAME SVID_PVDDCR_CPU1_P1_SVTI_R
J 0
(-7100 5485);
DISPLAY 0.489362 (-7100 5485);
FORCEPROP 2 LASTPROP $XRERR UNIQUE?
J 0
(-7340 5485);
DISPLAY 0.638298 (-7340 5485);
PAINT MONO (-7340 5485);
DISPLAY INVISIBLE (-7340 5485);
WIRE 16 -1 (-7275 5225)(-6375 5225);
FORCEPROP 2 LAST SIG_NAME SMB_CLK_PVDDCR_CPU1_P1_R
J 0
(-7110 5235);
DISPLAY 0.489362 (-7110 5235);
FORCEPROP 2 LASTPROP $XRERR UNIQUE?
J 0
(-7350 5235);
DISPLAY 0.638298 (-7350 5235);
PAINT MONO (-7350 5235);
DISPLAY INVISIBLE (-7350 5235);
WIRE 16 -1 (-6375 5625)(-7975 5625);
FORCEPROP 2 LAST SIG_NAME SVID_PVDDCR_CPU1_P1_SVTO_R
J 0
(-7100 5635);
DISPLAY 0.489362 (-7100 5635);
FORCEPROP 2 LASTPROP $XRERR UNIQUE?
J 0
(-7340 5635);
DISPLAY 0.638298 (-7340 5635);
PAINT MONO (-7340 5635);
DISPLAY INVISIBLE (-7340 5635);
WIRE 16 -1 (-7275 4925)(-6375 4925);
FORCEPROP 2 LAST SIG_NAME PVDDCR_CPU1_P1_SMB_ALERT_R
J 0
(-7110 4935);
DISPLAY 0.489362 (-7110 4935);
FORCEPROP 2 LASTPROP $XRERR UNIQUE?
J 0
(-7350 4935);
DISPLAY 0.638298 (-7350 4935);
PAINT MONO (-7350 4935);
DISPLAY INVISIBLE (-7350 4935);
WIRE 16 -1 (-7275 5075)(-6375 5075);
FORCEPROP 2 LAST SIG_NAME SMB_DIO_PVDDCR_CPU1_P1_R
J 0
(-7110 5085);
DISPLAY 0.489362 (-7110 5085);
FORCEPROP 2 LASTPROP $XRERR UNIQUE?
J 0
(-7350 5085);
DISPLAY 0.638298 (-7350 5085);
PAINT MONO (-7350 5085);
DISPLAY INVISIBLE (-7350 5085);
WIRE 16 -1 (-4375 3175)(-5025 3175);
FORCEPROP 2 LAST SIG_NAME NC_PVDDCR_CPU1_P1_IMON8
J 0
(-4960 3185);
DISPLAY 0.489362 (-4960 3185);
FORCEPROP 2 LASTPROP $XRERR UNIQUE?
J 0
(-5200 3185);
DISPLAY 0.638298 (-5200 3185);
PAINT MONO (-5200 3185);
DISPLAY INVISIBLE (-5200 3185);
WIRE 16 -1 (-4800 1475)(-5025 1475);
WIRE 16 -1 (-4800 1775)(-4800 1475);
WIRE 16 -1 (-4350 1775)(-4800 1775);
FORCEPROP 2 LAST SIG_NAME PVDDIO_P1_TEMP1
J 0
(-4710 1785);
DISPLAY 0.489362 (-4710 1785);
WIRE 16 -1 (-4350 1775)(-3800 1775);
WIRE 16 -1 (-4350 1775)(-4350 1675);
WIRE 16 -1 (-6650 2250)(-6500 2250);
WIRE 16 -1 (-6500 2250)(-6500 2375);
WIRE 16 -1 (-6375 2375)(-6500 2375);
FORCEPROP 2 LAST SIG_NAME PVDDCR_CPU1_P1_OCP_N_R
J 0
(-6985 2400);
DISPLAY 0.489362 (-6985 2400);
FORCEPROP 2 LASTPROP $XRERR UNIQUE?
J 0
(-7225 2400);
DISPLAY 0.638298 (-7225 2400);
PAINT MONO (-7225 2400);
DISPLAY INVISIBLE (-7225 2400);
WIRE 16 -1 (-7300 2375)(-6500 2375);
WIRE 16 -1 (-7575 3275)(-7225 3275);
WIRE 16 -1 (-6575 3275)(-7225 3275);
FORCEPROP 2 LAST SIG_NAME VSENSE_PVDDIO_P1_VSEN1
J 0
(-7035 3285);
DISPLAY 0.489362 (-7035 3285);
FORCEPROP 2 LASTPROP $XRERR UNIQUE?
J 0
(-7275 3285);
DISPLAY 0.638298 (-7275 3285);
PAINT MONO (-7275 3285);
DISPLAY INVISIBLE (-7275 3285);
WIRE 16 -1 (-7225 3200)(-7225 3275);
WIRE 16 -1 (-6575 3275)(-6575 3225);
WIRE 16 -1 (-6575 3225)(-6375 3225);
WIRE 16 -1 (-7325 2675)(-7225 2675);
WIRE 16 -1 (-7225 2675)(-7225 2525);
FORCEPROP 2 LAST SIG_NAME PVDDCR_CPU1_P1_RESET_N_R
J 0
(-7035 2535);
DISPLAY 0.489362 (-7035 2535);
FORCEPROP 2 LASTPROP $XRERR UNIQUE?
J 0
(-7275 2535);
DISPLAY 0.638298 (-7275 2535);
PAINT MONO (-7275 2535);
DISPLAY INVISIBLE (-7275 2535);
WIRE 16 -1 (-6375 2525)(-7225 2525);
WIRE 16 -1 (-7300 2525)(-7225 2525);
WIRE 16 -1 (-7875 2750)(-7875 2675);
WIRE 16 -1 (-7875 2675)(-7525 2675);
WIRE 16 -1 (-6450 750)(-6450 825);
WIRE 16 -1 (-6450 825)(-6375 825);
WIRE 16 -1 (-7175 850)(-7000 850);
WIRE 16 -1 (-7000 850)(-6650 850);
WIRE 16 -1 (-7000 750)(-7000 850);
WIRE 16 -1 (-6650 775)(-6650 850);
WIRE 16 -1 (-6650 850)(-6650 925);
FORCEPROP 2 LAST SIG_NAME PVDDCR_CPU1_P1_VINSEN
J 0
(-6810 950);
DISPLAY 0.489362 (-6810 950);
FORCEPROP 2 LASTPROP $XRERR UNIQUE?
J 0
(-7050 950);
DISPLAY 0.638298 (-7050 950);
PAINT MONO (-7050 950);
DISPLAY INVISIBLE (-7050 950);
WIRE 16 -1 (-6375 925)(-6650 925);
WIRE 16 -1 (-7575 2000)(-7575 2025);
WIRE 16 -1 (-7425 2000)(-7575 2000);
WIRE 16 -1 (-7425 2000)(-7425 2125);
WIRE 16 -1 (-7125 2000)(-7425 2000);
WIRE 16 -1 (-6375 2125)(-7425 2125);
WIRE 16 -1 (-7425 2250)(-7425 2125);
WIRE 16 -1 (-6850 2250)(-7425 2250);
WIRE 16 -1 (-7275 1275)(-7500 1275);
WIRE 16 -1 (-7500 1275)(-7500 1125);
WIRE 16 -1 (-7500 1275)(-7875 1275);
WIRE 16 -1 (-7500 1125)(-6375 1125);
FORCEPROP 2 LAST SIG_NAME PWRGD_PVDDIO_P1_R
J 0
(-6900 1135);
DISPLAY 0.489362 (-6900 1135);
FORCEPROP 2 LASTPROP $XRERR UNIQUE?
J 0
(-7140 1135);
DISPLAY 0.638298 (-7140 1135);
PAINT MONO (-7140 1135);
DISPLAY INVISIBLE (-7140 1135);
WIRE 16 -1 (-7875 1125)(-7500 1125);
WIRE 16 -1 (-7525 875)(-7525 850);
WIRE 16 -1 (-7525 850)(-7375 850);
WIRE 16 -1 (-8300 4925)(-7475 4925);
FORCEPROP 2 LAST SIG_NAME PVDDCR_CPU1_P1_SMB_ALERT
J 0
(-8285 4935);
DISPLAY 0.489362 (-8285 4935);
WIRE 16 -1 (-8800 6375)(-8175 6375);
FORCEPROP 2 LAST SIG_NAME PWRGD_PVDDCR_CPU1_P1
J 0
(-8810 6385);
DISPLAY 0.489362 (-8810 6385);
WIRE 16 -1 (-8800 6225)(-8175 6225);
FORCEPROP 2 LAST SIG_NAME FM_PVDDCR_CPU1_P1_EN
J 0
(-8810 6235);
DISPLAY 0.489362 (-8810 6235);
WIRE 16 -1 (-8300 5225)(-7475 5225);
FORCEPROP 2 LAST SIG_NAME SMB_SCM_6_R2_SCL
J 0
(-8085 5235);
DISPLAY 0.489362 (-8085 5235);
WIRE 16 -1 (-8300 5075)(-7475 5075);
FORCEPROP 2 LAST SIG_NAME SMB_SCM_6_R2_SDA
J 0
(-8085 5085);
DISPLAY 0.489362 (-8085 5085);
WIRE 16 -1 (-7800 775)(-7800 650);
WIRE 16 -1 (-7800 650)(-7800 600);
WIRE 16 -1 (-8250 650)(-7800 650);
WIRE 16 -1 (-8250 750)(-8250 650);
WIRE 16 -1 (-8250 950)(-8250 1025);
WIRE 16 -1 (-7800 1025)(-8250 1025);
WIRE 16 -1 (-8500 1025)(-8250 1025);
WIRE 16 -1 (-6375 1025)(-7800 1025);
FORCEPROP 2 LAST SIG_NAME PVDDCR_CPU1_P1_VMON
J 0
(-6900 1035);
DISPLAY 0.489362 (-6900 1035);
FORCEPROP 2 LASTPROP $XRERR UNIQUE?
J 0
(-7140 1035);
DISPLAY 0.638298 (-7140 1035);
PAINT MONO (-7140 1035);
DISPLAY INVISIBLE (-7140 1035);
WIRE 16 -1 (-7800 975)(-7800 1025);
WIRE 16 -1 (-8500 1775)(-8500 1825);
WIRE 16 -1 (-7350 1825)(-8500 1825);
WIRE 16 -1 (-8500 1825)(-8500 1900);
WIRE 16 -1 (-7350 1825)(-7350 1625);
WIRE 16 -1 (-6375 1625)(-7350 1625);
FORCEPROP 2 LAST SIG_NAME PVDDCR_CPU1_P1_EN1_ADDR_CFG
J 0
(-7160 1635);
DISPLAY 0.489362 (-7160 1635);
FORCEPROP 2 LASTPROP $XRERR UNIQUE?
J 0
(-7400 1635);
DISPLAY 0.638298 (-7400 1635);
PAINT MONO (-7400 1635);
DISPLAY INVISIBLE (-7400 1635);
WIRE 16 -1 (-10150 6500)(-9775 6500);
WIRE 16 -1 (-10150 6500)(-10150 6550);
WIRE 16 -1 (-10150 6350)(-10150 6500);
WIRE 16 -1 (-9775 6500)(-9600 6500);
WIRE 16 -1 (-9775 6500)(-9775 6350);
WIRE 16 -1 (-9600 6500)(-9400 6500);
WIRE 16 -1 (-9600 6350)(-9600 6500);
WIRE 16 -1 (-9400 6500)(-9400 6350);
WIRE 16 -1 (-10175 5925)(-9450 5925);
WIRE 16 -1 (-9450 5925)(-9400 5925);
WIRE 16 -1 (-9450 5375)(-9450 5925);
WIRE 16 -1 (-9400 5925)(-6375 5925);
FORCEPROP 2 LAST SIG_NAME SVID_PVDDCR_CPU1_P1_SVC_R
J 0
(-7100 5935);
DISPLAY 0.489362 (-7100 5935);
WIRE 16 -1 (-9400 6150)(-9400 5925);
WIRE 16 -1 (-10175 5775)(-9650 5775);
WIRE 16 -1 (-9650 5775)(-9600 5775);
WIRE 16 -1 (-9650 5375)(-9650 5775);
WIRE 16 -1 (-9600 5775)(-6375 5775);
FORCEPROP 2 LAST SIG_NAME SVID_PVDDCR_CPU1_P1_SVD_R
J 0
(-7100 5785);
DISPLAY 0.489362 (-7100 5785);
WIRE 16 -1 (-9600 6150)(-9600 5775);
WIRE 16 -1 (-10025 5375)(-10025 5625);
WIRE 16 -1 (-10025 5625)(-9850 5625);
WIRE 16 -1 (-10175 5625)(-10025 5625);
WIRE 16 -1 (-9850 5625)(-9775 5625);
WIRE 16 -1 (-9850 5350)(-9850 5625);
WIRE 16 -1 (-9775 5625)(-8175 5625);
FORCEPROP 2 LAST SIG_NAME SVID_PVDDCR_CPU1_P1_SVTO
J 0
(-8985 5635);
DISPLAY 0.489362 (-8985 5635);
WIRE 16 -1 (-9775 6150)(-9775 5625);
WIRE 16 -1 (-10200 5475)(-10150 5475);
WIRE 16 -1 (-10200 5475)(-10200 5375);
WIRE 16 -1 (-10150 5475)(-8175 5475);
FORCEPROP 2 LAST SIG_NAME SVID_PVDDCR_CPU1_P1_SVTI
J 0
(-8985 5500);
DISPLAY 0.489362 (-8985 5500);
FORCEPROP 2 LASTPROP $XRERR UNIQUE?
J 0
(-9225 5500);
DISPLAY 0.638298 (-9225 5500);
PAINT MONO (-9225 5500);
DISPLAY INVISIBLE (-9225 5500);
WIRE 16 -1 (-10150 6150)(-10150 5475);
WIRE 16 -1 (-10200 5175)(-10200 4975);
WIRE 16 -1 (-10200 4975)(-10025 4975);
WIRE 16 -1 (-10200 4975)(-10200 4875);
WIRE 16 -1 (-10025 5175)(-10025 4975);
WIRE 16 -1 (-10025 4975)(-9850 4975);
WIRE 16 -1 (-9850 5150)(-9850 4975);
WIRE 16 -1 (-9850 4975)(-9650 4975);
WIRE 16 -1 (-9650 5175)(-9650 4975);
WIRE 16 -1 (-9650 4975)(-9450 4975);
WIRE 16 -1 (-9450 4975)(-9450 5175);
WIRE 17 273 (-10150 3925)(-10150 4475);
WIRE 17 273 (-10150 3925)(-9800 3925);
WIRE 17 273 (-10150 4475)(-9800 4475);
WIRE 17 273 (-9800 4475)(-9800 3925);
WIRE 16 -1 (-8500 2575)(-9200 2575);
WIRE 16 -1 (-8500 2500)(-8500 2575);
WIRE 16 -1 (-9200 2575)(-9200 2600);
WIRE 16 -1 (-9200 2500)(-9200 2575);
WIRE 16 -1 (-9200 1925)(-9200 2200);
WIRE 16 -1 (-8800 2200)(-9200 2200);
FORCEPROP 2 LAST SIG_NAME PVDDIO_P1_EN_G
J 0
(-9160 2175);
DISPLAY 0.489362 (-9160 2175);
FORCEPROP 2 LASTPROP $XRERR UNIQUE?
J 0
(-9400 2175);
DISPLAY 0.638298 (-9400 2175);
PAINT MONO (-9400 2175);
DISPLAY INVISIBLE (-9400 2175);
WIRE 16 -1 (-9200 2300)(-9200 2200);
WIRE 17 273 (-10175 2825)(-10175 3375);
WIRE 17 273 (-10175 2825)(-9850 2825);
WIRE 17 273 (-10175 3375)(-9850 3375);
WIRE 17 273 (-9850 3375)(-9850 2825);
WIRE 16 -1 (-8300 1125)(-8300 1175);
WIRE 16 -1 (-8075 1125)(-8300 1125);
WIRE 16 -1 (-8300 1175)(-9075 1175);
FORCEPROP 2 LAST SIG_NAME PWRGD_PVDDIO_P1
J 0
(-9060 1185);
DISPLAY 0.489362 (-9060 1185);
WIRE 16 -1 (-9200 1550)(-8500 1550);
WIRE 16 -1 (-9200 1625)(-9200 1550);
WIRE 16 -1 (-9200 1550)(-9200 1475);
WIRE 16 -1 (-8500 1550)(-8500 1575);
WIRE 16 -1 (-9800 1725)(-9700 1725);
FORCEPROP 2 LAST SIG_NAME PVDDIO_P1_EN_R
J 0
(-9735 1735);
DISPLAY 0.489362 (-9735 1735);
FORCEPROP 2 LASTPROP $XRERR UNIQUE?
J 0
(-9975 1735);
DISPLAY 0.638298 (-9975 1735);
PAINT MONO (-9975 1735);
DISPLAY INVISIBLE (-9975 1735);
WIRE 16 -1 (-9350 1725)(-9700 1725);
WIRE 16 -1 (-9700 1725)(-9700 1650);
WIRE 16 -1 (-10350 1725)(-10000 1725);
FORCEPROP 2 LAST SIG_NAME PVDDIO_P1_EN
J 0
(-10360 1735);
DISPLAY 0.489362 (-10360 1735);
WIRE 16 -1 (-5025 3575)(-3950 3575);
FORCEPROP 2 LAST SIG_NAME NC_PVDDCR_CPU1_P1_PWM7
J 0
(-4860 3585);
DISPLAY 0.489362 (-4860 3585);
FORCEPROP 2 LASTPROP $XRERR UNIQUE?
J 0
(-3920 3575);
DISPLAY 0.638298 (-3920 3575);
PAINT MONO (-3920 3575);
DISPLAY INVISIBLE (-3920 3575);
WIRE 16 -1 (-3800 1175)(-4350 1175);
FORCEPROP 2 LAST SIG_NAME PVDDCR_CPU1_P1_TEMP0
J 0
(-4735 1185);
DISPLAY 0.489362 (-4735 1185);
WIRE 16 -1 (-4350 1175)(-4350 1100);
WIRE 16 -1 (-4350 1175)(-5025 1175);
WIRE 16 -1 (-8025 2375)(-7500 2375);
FORCEPROP 2 LAST SIG_NAME PVDDCR_CPU1_P1_OCP_N
J 0
(-8010 2385);
DISPLAY 0.489362 (-8010 2385);
WIRE 16 -1 (-8025 2525)(-7500 2525);
FORCEPROP 2 LAST SIG_NAME PVDDCR_CPU1_P1_RESET_N
J 0
(-8010 2535);
DISPLAY 0.489362 (-8010 2535);
WIRE 16 -1 (-5025 2975)(-3950 2975);
FORCEPROP 2 LAST SIG_NAME PVDDIO_P1_PWM4
J 0
(-4835 2985);
DISPLAY 0.489362 (-4835 2985);
WIRE 16 -1 (-5025 5075)(-3925 5075);
FORCEPROP 2 LAST SIG_NAME PVDDCR_CPU1_P1_PWM2
J 0
(-4835 5085);
DISPLAY 0.489362 (-4835 5085);
WIRE 16 -1 (-5025 4775)(-3950 4775);
FORCEPROP 2 LAST SIG_NAME PVDDCR_CPU1_P1_PWM3
J 0
(-4835 4785);
DISPLAY 0.489362 (-4835 4785);
WIRE 16 -1 (-5025 4675)(-3950 4675);
FORCEPROP 2 LAST SIG_NAME PVDDCR_CPU1_P1_IMON3
J 0
(-4835 4685);
DISPLAY 0.489362 (-4835 4685);
WIRE 16 -1 (-5025 2675)(-3950 2675);
FORCEPROP 0 LAST SIG_NAME PVDDIO_P1_PWM3
J 0
(-4835 2685);
DISPLAY 0.489362 (-4835 2685);
WIRE 16 -1 (-3950 2875)(-5025 2875);
FORCEPROP 2 LAST SIG_NAME PVDDIO_P1_IMON4
J 0
(-4835 2885);
DISPLAY 0.489362 (-4835 2885);
WIRE 16 -1 (-4375 3475)(-5025 3475);
FORCEPROP 2 LAST SIG_NAME NC_PVDDCR_CPU1_P1_IMON7
J 0
(-4935 3485);
DISPLAY 0.489362 (-4935 3485);
FORCEPROP 2 LASTPROP $XRERR UNIQUE?
J 0
(-5175 3485);
DISPLAY 0.638298 (-5175 3485);
PAINT MONO (-5175 3485);
DISPLAY INVISIBLE (-5175 3485);
WIRE 16 -1 (-5025 3275)(-3950 3275);
FORCEPROP 2 LAST SIG_NAME NC_PVDDCR_CPU1_P1_PWM8
J 0
(-4835 3285);
DISPLAY 0.489362 (-4835 3285);
FORCEPROP 2 LASTPROP $XRERR UNIQUE?
J 0
(-3920 3275);
DISPLAY 0.638298 (-3920 3275);
PAINT MONO (-3920 3275);
DISPLAY INVISIBLE (-3920 3275);
WIRE 16 -1 (-3975 3775)(-5025 3775);
FORCEPROP 2 LAST SIG_NAME PVDDCR_CPU1_P1_IMON6
J 0
(-4835 3785);
DISPLAY 0.489362 (-4835 3785);
WIRE 16 -1 (-5025 4075)(-3950 4075);
FORCEPROP 2 LAST SIG_NAME PVDDCR_CPU1_P1_IMON5
J 0
(-4835 4085);
DISPLAY 0.489362 (-4835 4085);
WIRE 16 -1 (-5025 4475)(-3950 4475);
FORCEPROP 2 LAST SIG_NAME PVDDCR_CPU1_P1_PWM4
J 0
(-4835 4485);
DISPLAY 0.489362 (-4835 4485);
WIRE 16 -1 (-7625 4375)(-7275 4375);
WIRE 16 -1 (-6575 4375)(-7275 4375);
FORCEPROP 2 LAST SIG_NAME VSENSE_PVDDCR_CPU1_P1_VSEN0
J 0
(-7160 4385);
DISPLAY 0.489362 (-7160 4385);
FORCEPROP 2 LASTPROP $XRERR UNIQUE?
J 0
(-7400 4385);
DISPLAY 0.638298 (-7400 4385);
PAINT MONO (-7400 4385);
DISPLAY INVISIBLE (-7400 4385);
WIRE 16 -1 (-7275 4300)(-7275 4375);
WIRE 16 -1 (-6575 4375)(-6575 4325);
WIRE 16 -1 (-6575 4325)(-6375 4325);
WIRE 17 273 (-10450 400)(-9250 400);
WIRE 17 273 (-10450 800)(-10450 400);
WIRE 17 273 (-9250 800)(-9250 400);
WIRE 17 273 (-10450 800)(-9250 800);
DOT 1 (-7800 1025);
DOT 1 (-7225 3275);
DOT 1 (-7500 1275);
DOT 1 (-8850 3275);
DOT 1 (-8250 1025);
DOT 1 (-7800 650);
DOT 1 (-6650 850);
DOT 1 (-7000 850);
DOT 1 (-9700 1725);
DOT 1 (-9200 1550);
DOT 1 (-8500 1825);
DOT 1 (-9200 2200);
DOT 1 (-9200 2575);
DOT 1 (-8850 2900);
DOT 1 (-8850 4000);
DOT 1 (-10025 4975);
DOT 1 (-9850 4975);
DOT 1 (-9650 4975);
DOT 1 (-10150 5475);
DOT 1 (-10025 5625);
DOT 1 (-9850 5625);
DOT 1 (-9775 5625);
DOT 1 (-9650 5775);
DOT 1 (-9450 5925);
DOT 1 (-8850 4375);
DOT 1 (-10150 6500);
DOT 1 (-9775 6500);
DOT 1 (-9600 6500);
DOT 1 (-7500 1125);
DOT 1 (-7425 2000);
DOT 1 (-7425 2125);
DOT 1 (-7225 2525);
DOT 1 (-7225 2900);
DOT 1 (-7275 4000);
DOT 1 (-6500 2375);
DOT 1 (-4350 1175);
DOT 1 (-4350 1775);
DOT 1 (-7275 4375);
DOT 1 (-7550 6225);
DOT 1 (-7550 6375);
DOT 1 (-7550 6525);
DOT 1 (-4725 5900);
DOT 1 (-4725 6375);
DOT 1 (-4350 6375);
DOT 1 (-9400 5925);
DOT 1 (-9600 5775);
DOT 1 (-4350 5900);
DOT 1 (-10200 4975);
FORCENOTE
/42.2K
(-9575 475) 0;
DISPLAY LEFT (-9575 475);
DISPLAY 0.638298 (-9575 475);
PAINT WHITE (-9575 475);
FORCENOTE
VR
(-10375 725) 0;
DISPLAY LEFT (-10375 725);
DISPLAY 0.808511 (-10375 725);
PAINT WHITE (-10375 725);
FORCENOTE
/2K
(-9575 550) 0;
DISPLAY LEFT (-9575 550);
DISPLAY 0.638298 (-9575 550);
PAINT WHITE (-9575 550);
FORCENOTE
1/6.65K
(-9575 625) 0;
DISPLAY LEFT (-9575 625);
DISPLAY 0.638298 (-9575 625);
PAINT WHITE (-9575 625);
FORCENOTE
0X4C
(-9925 550) 0;
DISPLAY LEFT (-9925 550);
DISPLAY 0.638298 (-9925 550);
PAINT WHITE (-9925 550);
FORCENOTE
0X4C
(-9925 475) 0;
DISPLAY LEFT (-9925 475);
DISPLAY 0.638298 (-9925 475);
PAINT WHITE (-9925 475);
FORCENOTE
MPS
(-10375 475) 0;
DISPLAY LEFT (-10375 475);
DISPLAY 0.638298 (-10375 475);
PAINT WHITE (-10375 475);
FORCENOTE
INFINEON
(-10375 550) 0;
DISPLAY LEFT (-10375 550);
DISPLAY 0.638298 (-10375 550);
PAINT WHITE (-10375 550);
FORCENOTE
RENESAS
(-10375 625) 0;
DISPLAY LEFT (-10375 625);
DISPLAY 0.638298 (-10375 625);
PAINT WHITE (-10375 625);
FORCENOTE
0X74
(-9925 625) 0;
DISPLAY LEFT (-9925 625);
DISPLAY 0.638298 (-9925 625);
PAINT WHITE (-9925 625);
FORCENOTE
PMBUS ADDRESS AND CONFIG
(-10475 850) 0;
DISPLAY LEFT (-10475 850);
DISPLAY 1.170213 (-10475 850);
PAINT WHITE (-10475 850);
FORCENOTE
PU34=AR0T6GPV005
(-2925 3675) 0;
DISPLAY LEFT (-2925 3675);
DISPLAY 1.021277 (-2925 3675);
PAINT WHITE (-2925 3675);
FORCENOTE
2ND SOURCE:INFENEON BOM
(-2925 3550) 0;
DISPLAY LEFT (-2925 3550);
DISPLAY 1.021277 (-2925 3550);
PAINT WHITE (-2925 3550);
FORCENOTE
BOM NOTE
(-2925 3850) 0;
DISPLAY LEFT (-2925 3850);
DISPLAY 1.021277 (-2925 3850);
PAINT WHITE (-2925 3850);
FORCENOTE
PU34=AR0T6GPV000
(-2925 3475) 0;
DISPLAY LEFT (-2925 3475);
DISPLAY 1.021277 (-2925 3475);
PAINT WHITE (-2925 3475);
FORCENOTE
MAIN SOURCE:RENESAS BOM
(-2925 3750) 0;
DISPLAY LEFT (-2925 3750);
DISPLAY 1.021277 (-2925 3750);
PAINT WHITE (-2925 3750);
FORCENOTE
PR244=CS22002FB02
(-2925 3400) 0;
DISPLAY LEFT (-2925 3400);
DISPLAY 1.021277 (-2925 3400);
PAINT WHITE (-2925 3400);
FORCENOTE
PC366 = CH5103KEB01
(-2925 3325) 0;
DISPLAY LEFT (-2925 3325);
DISPLAY 1.021277 (-2925 3325);
PAINT WHITE (-2925 3325);
FORCENOTE
TRACE SPACING = 5MIL
(-10400 2575) 0;
DISPLAY LEFT (-10400 2575);
DISPLAY 1.021277 (-10400 2575);
PAINT WHITE (-10400 2575);
FORCENOTE
TRACE WIDTH = 10MIL
(-10400 2650) 0;
DISPLAY LEFT (-10400 2650);
DISPLAY 1.021277 (-10400 2650);
PAINT WHITE (-10400 2650);
FORCENOTE
DIFFERENTIAL PAIR
(-10400 2725) 0;
DISPLAY LEFT (-10400 2725);
DISPLAY 1.021277 (-10400 2725);
PAINT WHITE (-10400 2725);
FORCENOTE
WORK FREQUENCY=600KHZ
(-2875 4600) 0;
DISPLAY LEFT (-2875 4600);
DISPLAY 0.936170 (-2875 4600);
PAINT WHITE (-2875 4600);
FORCENOTE
EFFICIENCY > 90% @TDC
(-2875 4525) 0;
DISPLAY LEFT (-2875 4525);
DISPLAY 0.936170 (-2875 4525);
PAINT WHITE (-2875 4525);
FORCENOTE
SVI3 ADDRESS=PORT1 (0X2)
(-2875 4450) 0;
DISPLAY LEFT (-2875 4450);
DISPLAY 0.936170 (-2875 4450);
PAINT WHITE (-2875 4450);
FORCENOTE
CONFIG
(-9575 725) 0;
DISPLAY LEFT (-9575 725);
DISPLAY 0.808511 (-9575 725);
PAINT WHITE (-9575 725);
FORCENOTE
ADDRESS
(-9925 725) 0;
DISPLAY LEFT (-9925 725);
DISPLAY 0.808511 (-9925 725);
PAINT WHITE (-9925 725);
FORCENOTE
TRACE SPACING = 5MIL
(-10200 3675) 0;
DISPLAY LEFT (-10200 3675);
DISPLAY 1.021277 (-10200 3675);
PAINT WHITE (-10200 3675);
FORCENOTE
TRACE WIDTH = 10MIL
(-10200 3750) 0;
DISPLAY LEFT (-10200 3750);
DISPLAY 1.021277 (-10200 3750);
PAINT WHITE (-10200 3750);
FORCENOTE
DIFFERENTIAL PAIR
(-10200 3825) 0;
DISPLAY LEFT (-10200 3825);
DISPLAY 1.021277 (-10200 3825);
PAINT WHITE (-10200 3825);
FORCENOTE
EDC=140A
(-2875 4900) 0;
DISPLAY LEFT (-2875 4900);
DISPLAY 0.936170 (-2875 4900);
PAINT WHITE (-2875 4900);
FORCENOTE
OCP=168A (EDC*1.2)
(-2875 4825) 0;
DISPLAY LEFT (-2875 4825);
DISPLAY 0.936170 (-2875 4825);
PAINT WHITE (-2875 4825);
FORCENOTE
LOAD RELEASE=37A
(-2875 4675) 0;
DISPLAY LEFT (-2875 4675);
DISPLAY 0.936170 (-2875 4675);
PAINT WHITE (-2875 4675);
FORCENOTE
DC & AC=+/-80MV
(-2875 5050) 0;
DISPLAY LEFT (-2875 5050);
DISPLAY 0.936170 (-2875 5050);
PAINT WHITE (-2875 5050);
FORCENOTE
TDC=120A
(-2875 4975) 0;
DISPLAY LEFT (-2875 4975);
DISPLAY 0.936170 (-2875 4975);
PAINT WHITE (-2875 4975);
FORCENOTE
LOAD STEP=200A
(-2875 5900) 0;
DISPLAY LEFT (-2875 5900);
DISPLAY 0.936170 (-2875 5900);
PAINT WHITE (-2875 5900);
FORCENOTE
LOAD-LINE=0.4MOHM
(-2875 5750) 0;
DISPLAY LEFT (-2875 5750);
DISPLAY 0.936170 (-2875 5750);
PAINT WHITE (-2875 5750);
FORCENOTE
VID=0.9-1.2V
(-2875 5200) 0;
DISPLAY LEFT (-2875 5200);
DISPLAY 0.936170 (-2875 5200);
PAINT WHITE (-2875 5200);
FORCENOTE
RIPPLE=+/-10MV
(-2875 5125) 0;
DISPLAY LEFT (-2875 5125);
DISPLAY 0.936170 (-2875 5125);
PAINT WHITE (-2875 5125);
FORCENOTE
MAX AC=+200MV
(-2875 6275) 0;
DISPLAY LEFT (-2875 6275);
DISPLAY 0.936170 (-2875 6275);
PAINT WHITE (-2875 6275);
FORCENOTE
RIPPLE=+/-10MV
(-2875 6425) 0;
DISPLAY LEFT (-2875 6425);
DISPLAY 0.936170 (-2875 6425);
PAINT WHITE (-2875 6425);
FORCENOTE
DC=+/-20MV
(-2875 6350) 0;
DISPLAY LEFT (-2875 6350);
DISPLAY 0.936170 (-2875 6350);
PAINT WHITE (-2875 6350);
FORCENOTE
EFFICIENCY > 90% @TDC
(-2875 5600) 0;
DISPLAY LEFT (-2875 5600);
DISPLAY 0.936170 (-2875 5600);
PAINT WHITE (-2875 5600);
FORCENOTE
WORK FREQUENCY=600KHZ
(-2875 5675) 0;
DISPLAY LEFT (-2875 5675);
DISPLAY 0.936170 (-2875 5675);
PAINT WHITE (-2875 5675);
FORCENOTE
VID=0.55-2V
(-2875 6500) 0;
DISPLAY LEFT (-2875 6500);
DISPLAY 0.936170 (-2875 6500);
PAINT WHITE (-2875 6500);
FORCENOTE
PVDDCR_CPU1_P1 SPECFICATION
(-2875 6622) 0;
DISPLAY LEFT (-2875 6622);
DISPLAY 1.170213 (-2875 6622);
PAINT WHITE (-2875 6622);
FORCENOTE
TDC=175A
(-2875 6125) 0;
DISPLAY LEFT (-2875 6125);
DISPLAY 0.936170 (-2875 6125);
PAINT WHITE (-2875 6125);
FORCENOTE
LOAD STEP=44A
(-2875 4750) 0;
DISPLAY LEFT (-2875 4750);
DISPLAY 0.936170 (-2875 4750);
PAINT WHITE (-2875 4750);
FORCENOTE
MIN AC=VID-EDC*LL-110MV
(-2875 6200) 0;
DISPLAY LEFT (-2875 6200);
DISPLAY 0.936170 (-2875 6200);
PAINT WHITE (-2875 6200);
FORCENOTE
EDC=230A
(-2875 6050) 0;
DISPLAY LEFT (-2875 6050);
DISPLAY 0.936170 (-2875 6050);
PAINT WHITE (-2875 6050);
FORCENOTE
OCP=276A (EDC*1.2)
(-2875 5975) 0;
DISPLAY LEFT (-2875 5975);
DISPLAY 0.936170 (-2875 5975);
PAINT WHITE (-2875 5975);
FORCENOTE
LOAD RELEASE=200A
(-2875 5825) 0;
DISPLAY LEFT (-2875 5825);
DISPLAY 0.936170 (-2875 5825);
PAINT WHITE (-2875 5825);
FORCENOTE
SVI3 ADDRESS=PORT1 (0X1)
(-2875 5525) 0;
DISPLAY LEFT (-2875 5525);
DISPLAY 0.936170 (-2875 5525);
PAINT WHITE (-2875 5525);
FORCENOTE
PVDDIO_P1 SPECFICATION
(-2875 5325) 0;
DISPLAY LEFT (-2875 5325);
DISPLAY 1.276596 (-2875 5325);
PAINT WHITE (-2875 5325);
FORCENOTE
3RD SOURCE:MPS BOM
(-2950 2625) 0;
DISPLAY LEFT (-2950 2625);
DISPLAY 1.021277 (-2950 2625);
PAINT WHITE (-2950 2625);
FORCENOTE
PU34=AL002857000
(-2950 2550) 0;
DISPLAY LEFT (-2950 2550);
DISPLAY 1.021277 (-2950 2550);
PAINT WHITE (-2950 2550);
FORCENOTE
PR244=TMP_QCS34222FB00
(-2950 2475) 0;
DISPLAY LEFT (-2950 2475);
DISPLAY 1.021277 (-2950 2475);
PAINT WHITE (-2950 2475);
FORCENOTE
PC358,PC361,PR230,PC357=EMPTY
(-2950 2400) 0;
DISPLAY LEFT (-2950 2400);
DISPLAY 1.021277 (-2950 2400);
PAINT WHITE (-2950 2400);
FORCENOTE
PR533,PR12=EMPTY
(-2950 2325) 0;
DISPLAY LEFT (-2950 2325);
DISPLAY 1.021277 (-2950 2325);
PAINT WHITE (-2950 2325);
FORCENOTE
PR231=CS00002JB38
(-2950 2250) 0;
DISPLAY LEFT (-2950 2250);
DISPLAY 1.021277 (-2950 2250);
PAINT WHITE (-2950 2250);
FORCENOTE
PR251=CS37502FB05
(-2950 2175) 0;
DISPLAY LEFT (-2950 2175);
DISPLAY 1.021277 (-2950 2175);
PAINT WHITE (-2950 2175);
FORCENOTE
PC364=TMP_QCH21006JB10
(-2950 2100) 0;
DISPLAY LEFT (-2950 2100);
DISPLAY 1.021277 (-2950 2100);
PAINT WHITE (-2950 2100);
FORCENOTE
PC367,PC368=TMP_QCH31004KB17
(-2950 1950) 0;
DISPLAY LEFT (-2950 1950);
DISPLAY 1.021277 (-2950 1950);
PAINT WHITE (-2950 1950);
FORCENOTE
PR603=CS24992FB07
(-2950 2025) 0;
DISPLAY LEFT (-2950 2025);
DISPLAY 1.021277 (-2950 2025);
PAINT WHITE (-2950 2025);
FORCENOTE
PC367,PC368 = CH11006JB00
(-2925 3250) 0;
DISPLAY LEFT (-2925 3250);
DISPLAY 1.021277 (-2925 3250);
PAINT WHITE (-2925 3250);
FORCENOTE
PC358,PC361 = CH12206KB14
(-2925 3175) 0;
DISPLAY LEFT (-2925 3175);
DISPLAY 1.021277 (-2925 3175);
PAINT WHITE (-2925 3175);
FORCENOTE
PR230 = CS25362FB15
(-2925 3100) 0;
DISPLAY LEFT (-2925 3100);
DISPLAY 1.021277 (-2925 3100);
PAINT WHITE (-2925 3100);
FORCENOTE
PR231 = CS21002FB24
(-2925 3025) 0;
DISPLAY LEFT (-2925 3025);
DISPLAY 1.021277 (-2925 3025);
PAINT WHITE (-2925 3025);
FORCENOTE
PR12,PR533 = EMPTY
(-2925 2950) 0;
DISPLAY LEFT (-2925 2950);
DISPLAY 1.021277 (-2925 2950);
PAINT WHITE (-2925 2950);
FORCENOTE
PR217 = CS00002JB38
(-2925 2875) 0;
DISPLAY LEFT (-2925 2875);
DISPLAY 1.021277 (-2925 2875);
PAINT WHITE (-2925 2875);
FORCENOTE
PC357 = CH3104J1B00
(-2925 2800) 0;
DISPLAY LEFT (-2925 2800);
DISPLAY 1.021277 (-2925 2800);
PAINT WHITE (-2925 2800);
QUIT
